FILE_TYPE = MACRO_DRAWING;
SET COLOR_WIRE YELLOW;
SET COLOR_PROP MONO;
SET COLOR_DOT WHITE;
SET COLOR_ARC YELLOW;
SET COLOR_BODY GREEN;
SET COLOR_NOTE MONO;
SET PROP_DISPLAY VALUE;
SET PAGE_NUMBER P224;
FORCEADD PVDDQ_GHJ..1
(4500 2050);
FORCEPROP 3 LASTPIN (4500 2000) SIG_NAME PVDDQ_GHJ\g
J 0
(4510 2010);
DISPLAY 0.659574 (4510 2010);
PAINT MONO (4510 2010);
DISPLAY INVISIBLE (4510 2010);
FORCEPROP 1 LAST VOLTAGE 1.2V
J 0
(4455 2007);
DISPLAY 0.340426 (4455 2007);
PAINT SKYBLUE (4455 2007);
DISPLAY INVISIBLE (4455 2007);
FORCEPROP 1 LAST PATH I1
J 0
(4550 2075);
DISPLAY 0.872340 (4550 2075);
PAINT AQUA (4550 2075);
DISPLAY INVISIBLE (4550 2075);
FORCEPROP 2 LAST CDS_LIB mstr_symbols
J 0
(4500 2050);
PAINT ORANGE (4500 2050);
DISPLAY INVISIBLE (4500 2050);
FORCEPROP 1 LAST BODY_TYPE PLUMBING
J 0
(4455 2007);
DISPLAY 0.340426 (4455 2007);
PAINT GREEN (4455 2007);
DISPLAY INVISIBLE (4455 2007);
FORCEPROP 1 LAST HDL_POWER PVDDQ_GHJ
J 1
(4500 2100);
DISPLAY 0.872340 (4500 2100);
PAINT GREEN (4500 2100);
DISPLAY INVISIBLE (4500 2100);
FORCEADD IR354XX..1
(1825 2250);
FORCEPROP 2 LASTPIN (2325 1800) $PN 40
J 0
(2335 1810);
DISPLAY 0.617021 (2335 1810);
PAINT ORANGE (2335 1810);
FORCEPROP 2 LASTPIN (1325 2300) $PN 41
J 2
(1315 2310);
DISPLAY 0.617021 (1315 2310);
PAINT ORANGE (1315 2310);
FORCEPROP 2 LASTPIN (1325 1900) $PN 32
J 2
(1315 1910);
DISPLAY 0.617021 (1315 1910);
PAINT ORANGE (1315 1910);
FORCEPROP 2 LASTPIN (1325 1950) $PN 33
J 2
(1315 1960);
DISPLAY 0.617021 (1315 1960);
PAINT ORANGE (1315 1960);
FORCEPROP 2 LASTPIN (2325 1950) $PN 10
J 0
(2335 1960);
DISPLAY 0.617021 (2335 1960);
PAINT ORANGE (2335 1960);
FORCEPROP 1 LAST PART_NUMBER H73688-001
J 0
(1425 1550);
DISPLAY 0.617021 (1425 1550);
PAINT BLUE (1425 1550);
FORCEPROP 2 LASTPIN (1325 2150) $PN 34
J 2
(1315 2160);
DISPLAY 0.617021 (1315 2160);
PAINT ORANGE (1315 2160);
FORCEPROP 2 LASTPIN (1325 2700) $PN 25
J 2
(1315 2710);
DISPLAY 0.617021 (1315 2710);
PAINT ORANGE (1315 2710);
FORCEPROP 2 LAST NO_XNET_CONNECTION 1
J 0
(1375 3100);
PAINT MONO (1375 3100);
FORCEPROP 2 LASTPIN (2325 2800) $PN 38
J 0
(2335 2810);
DISPLAY 0.617021 (2335 2810);
PAINT ORANGE (2335 2810);
FORCEPROP 2 LASTPIN (2325 2550) $PN 31
J 0
(2335 2560);
DISPLAY 0.617021 (2335 2560);
PAINT ORANGE (2335 2560);
FORCEPROP 1 LAST MATERIAL IC
J 0
(1375 3000);
DISPLAY 0.617021 (1375 3000);
PAINT SKYBLUE (1375 3000);
FORCEPROP 2 LASTPIN (1325 2800) $PN 3
J 2
(1315 2810);
DISPLAY 0.617021 (1315 2810);
PAINT ORANGE (1315 2810);
FORCEPROP 2 LASTPIN (1325 2600) $PN 4
J 2
(1315 2610);
DISPLAY 0.617021 (1315 2610);
PAINT ORANGE (1315 2610);
FORCEPROP 2 LASTPIN (1325 2750) $PN 30
J 2
(1315 2760);
DISPLAY 0.617021 (1315 2760);
PAINT ORANGE (1315 2760);
FORCEPROP 2 LASTPIN (1325 2400) $PN 1
J 2
(1315 2410);
DISPLAY 0.617021 (1315 2410);
PAINT ORANGE (1315 2410);
FORCEPROP 2 LASTPIN (1325 2500) $PN 35
J 2
(1315 2510);
DISPLAY 0.617021 (1315 2510);
PAINT ORANGE (1315 2510);
FORCEPROP 2 LASTPIN (1325 2050) $PN 39
J 2
(1315 2060);
DISPLAY 0.617021 (1315 2060);
PAINT ORANGE (1315 2060);
FORCEPROP 2 LASTPIN (1325 2250) $PN 6
J 2
(1315 2260);
DISPLAY 0.617021 (1315 2260);
PAINT ORANGE (1315 2260);
FORCEPROP 2 LASTPIN (2325 1750) $PN 7
J 0
(2335 1760);
DISPLAY 0.617021 (2335 1760);
PAINT ORANGE (2335 1760);
FORCEPROP 2 LASTPIN (2325 1700) $PN 5
J 0
(2335 1710);
DISPLAY 0.617021 (2335 1710);
PAINT ORANGE (2335 1710);
FORCEPROP 2 LASTPIN (2325 1850) $PN 2
J 0
(2335 1860);
DISPLAY 0.617021 (2335 1860);
PAINT ORANGE (2335 1860);
FORCEPROP 2 LASTPIN (2325 2300) $PN 36
J 0
(2335 2310);
DISPLAY 0.617021 (2335 2310);
PAINT ORANGE (2335 2310);
FORCEPROP 2 LASTPIN (2325 2600) $PN 37
J 0
(2335 2610);
DISPLAY 0.617021 (2335 2610);
PAINT ORANGE (2335 2610);
FORCEPROP 1 LAST LOCATION EU1G1
J 0
(1375 3050);
DISPLAY 0.617021 (1375 3050);
PAINT AQUA (1375 3050);
FORCEPROP 1 LAST PACK_TYPE SM
J 0
(1375 3100);
PAINT SKYBLUE (1375 3100);
DISPLAY INVISIBLE (1375 3100);
FORCEPROP 2 LAST SEC_TYPE SM
J 0
(1375 3100);
DISPLAY 1.021277 (1375 3100);
PAINT ORANGE (1375 3100);
DISPLAY INVISIBLE (1375 3100);
FORCEPROP 2 LAST SEC 1
J 0
(1375 3100);
DISPLAY 0.680851 (1375 3100);
PAINT MONO (1375 3100);
DISPLAY INVISIBLE (1375 3100);
FORCEPROP 2 LAST CDS_LOCATION EU1G1
J 0
(1375 3050);
PAINT GREEN (1375 3050);
DISPLAY INVISIBLE (1375 3050);
FORCEPROP 2 LAST CDS_LIB mstr_discrete
J 0
(1825 2250);
PAINT ORANGE (1825 2250);
DISPLAY INVISIBLE (1825 2250);
FORCEPROP 1 LAST PATH I110
J 0
(1825 3000);
PAINT GREEN (1825 3000);
DISPLAY INVISIBLE (1825 3000);
FORCEPROP 1 LAST VALUE IR35411
J 1
(1825 2875);
DISPLAY 0.617021 (1825 2875);
PAINT SKYBLUE (1825 2875);
DISPLAY INVISIBLE (1825 2875);
FORCEADD IR354XX..1
(1850 -125);
FORCEPROP 0 LAST BOM_SS NOPOP
J 0
(1525 -875);
DISPLAY 0.638298 (1525 -875);
PAINT BROWN (1525 -875);
DISPLAY BOTH (1525 -875);
FORCEPROP 1 LAST MATERIAL IC
J 0
(1400 625);
DISPLAY 0.617021 (1400 625);
PAINT SKYBLUE (1400 625);
FORCEPROP 2 LASTPIN (2350 -575) $PN 40
J 0
(2360 -565);
DISPLAY 0.617021 (2360 -565);
PAINT ORANGE (2360 -565);
FORCEPROP 2 LASTPIN (1350 125) $PN 35
J 2
(1340 135);
DISPLAY 0.617021 (1340 135);
PAINT ORANGE (1340 135);
FORCEPROP 2 LASTPIN (1350 -325) $PN 39
J 2
(1340 -315);
DISPLAY 0.617021 (1340 -315);
PAINT ORANGE (1340 -315);
FORCEPROP 2 LASTPIN (1350 -475) $PN 32
J 2
(1340 -465);
DISPLAY 0.617021 (1340 -465);
PAINT ORANGE (1340 -465);
FORCEPROP 2 LASTPIN (1350 425) $PN 3
J 2
(1340 435);
DISPLAY 0.617021 (1340 435);
PAINT ORANGE (1340 435);
FORCEPROP 2 LASTPIN (2350 -675) $PN 5
J 0
(2360 -665);
DISPLAY 0.617021 (2360 -665);
PAINT ORANGE (2360 -665);
FORCEPROP 2 LASTPIN (2350 175) $PN 31
J 0
(2360 185);
DISPLAY 0.617021 (2360 185);
PAINT ORANGE (2360 185);
FORCEPROP 2 LASTPIN (1350 325) $PN 25
J 2
(1340 335);
DISPLAY 0.617021 (1340 335);
PAINT ORANGE (1340 335);
FORCEPROP 2 LASTPIN (1350 225) $PN 4
J 2
(1340 235);
DISPLAY 0.617021 (1340 235);
PAINT ORANGE (1340 235);
FORCEPROP 2 LASTPIN (1350 25) $PN 1
J 2
(1340 35);
DISPLAY 0.617021 (1340 35);
PAINT ORANGE (1340 35);
FORCEPROP 2 LASTPIN (2350 -525) $PN 2
J 0
(2360 -515);
DISPLAY 0.617021 (2360 -515);
PAINT ORANGE (2360 -515);
FORCEPROP 2 LASTPIN (2350 -625) $PN 7
J 0
(2360 -615);
DISPLAY 0.617021 (2360 -615);
PAINT ORANGE (2360 -615);
FORCEPROP 2 LASTPIN (1350 -125) $PN 6
J 2
(1340 -115);
DISPLAY 0.617021 (1340 -115);
PAINT ORANGE (1340 -115);
FORCEPROP 2 LASTPIN (2350 225) $PN 37
J 0
(2360 235);
DISPLAY 0.617021 (2360 235);
PAINT ORANGE (2360 235);
FORCEPROP 2 LASTPIN (1350 375) $PN 30
J 2
(1340 385);
DISPLAY 0.617021 (1340 385);
PAINT ORANGE (1340 385);
FORCEPROP 2 LASTPIN (2350 -425) $PN 10
J 0
(2360 -415);
DISPLAY 0.617021 (2360 -415);
PAINT ORANGE (2360 -415);
FORCEPROP 1 LAST PART_NUMBER H73688-001
J 0
(1400 -825);
DISPLAY 0.617021 (1400 -825);
PAINT BLUE (1400 -825);
FORCEPROP 2 LASTPIN (2350 425) $PN 38
J 0
(2360 435);
DISPLAY 0.617021 (2360 435);
PAINT ORANGE (2360 435);
FORCEPROP 2 LASTPIN (1350 -75) $PN 41
J 2
(1340 -65);
DISPLAY 0.617021 (1340 -65);
PAINT ORANGE (1340 -65);
FORCEPROP 2 LASTPIN (1350 -425) $PN 33
J 2
(1340 -415);
DISPLAY 0.617021 (1340 -415);
PAINT ORANGE (1340 -415);
FORCEPROP 2 LASTPIN (1350 -225) $PN 34
J 2
(1340 -215);
DISPLAY 0.617021 (1340 -215);
PAINT ORANGE (1340 -215);
FORCEPROP 2 LASTPIN (2350 -75) $PN 36
J 0
(2360 -65);
DISPLAY 0.617021 (2360 -65);
PAINT ORANGE (2360 -65);
FORCEPROP 1 LAST LOCATION EU1F1
J 0
(1400 675);
DISPLAY 0.617021 (1400 675);
PAINT AQUA (1400 675);
FORCEPROP 1 LAST PACK_TYPE SM
J 0
(1400 725);
PAINT SKYBLUE (1400 725);
DISPLAY INVISIBLE (1400 725);
FORCEPROP 2 LAST SEC_TYPE SM
J 0
(1400 725);
DISPLAY 1.021277 (1400 725);
PAINT ORANGE (1400 725);
DISPLAY INVISIBLE (1400 725);
FORCEPROP 2 LAST SEC 1
J 0
(1400 725);
DISPLAY 0.680851 (1400 725);
PAINT MONO (1400 725);
DISPLAY INVISIBLE (1400 725);
FORCEPROP 2 LAST CDS_LOCATION EU1F1
J 0
(1400 675);
PAINT GREEN (1400 675);
DISPLAY INVISIBLE (1400 675);
FORCEPROP 1 LAST PATH I111
J 0
(1850 625);
PAINT GREEN (1850 625);
DISPLAY INVISIBLE (1850 625);
FORCEPROP 2 LAST CDS_LIB mstr_discrete
J 0
(1850 -125);
PAINT ORANGE (1850 -125);
DISPLAY INVISIBLE (1850 -125);
FORCEPROP 1 LAST VALUE IR35411
J 1
(1850 500);
DISPLAY 0.617021 (1850 500);
PAINT SKYBLUE (1850 500);
DISPLAY INVISIBLE (1850 500);
FORCEADD RES..2
(4625 2400);
FORCEPROP 1 LAST VALUE 68.1K
J 0
(4670 2475);
DISPLAY 0.617021 (4670 2475);
PAINT SKYBLUE (4670 2475);
FORCEPROP 1 LAST TOLERANCE 1%
J 0
(4670 2425);
DISPLAY 0.617021 (4670 2425);
PAINT SKYBLUE (4670 2425);
FORCEPROP 1 LASTPIN (4625 2300) $PN 2
J 0
(4630 2310);
DISPLAY 0.787234 (4630 2310);
PAINT ORANGE (4630 2310);
FORCEPROP 1 LAST LOCATION R1G26
J 0
(4670 2525);
DISPLAY 0.617021 (4670 2525);
PAINT AQUA (4670 2525);
FORCEPROP 1 LAST MATERIAL EMPTY
J 0
(4665 2325);
DISPLAY 0.617021 (4665 2325);
PAINT RED (4665 2325);
FORCEPROP 1 LAST WATTAGE 1/16W
J 0
(4665 2375);
DISPLAY 0.617021 (4665 2375);
PAINT SKYBLUE (4665 2375);
FORCEPROP 1 LASTPIN (4625 2500) $PN 1
J 0
(4630 2462);
DISPLAY 0.787234 (4630 2462);
PAINT ORANGE (4630 2462);
FORCEPROP 1 LAST PACK_TYPE 0402
J 0
(4665 2225);
DISPLAY 0.617021 (4665 2225);
PAINT SKYBLUE (4665 2225);
FORCEPROP 1 LAST PART_NUMBER G21796-187
J 0
(4665 2275);
DISPLAY 0.617021 (4665 2275);
PAINT BLUE (4665 2275);
FORCEPROP 2 LAST SEC_TYPE 0402
J 0
(4675 2625);
DISPLAY 1.021277 (4675 2625);
PAINT ORANGE (4675 2625);
DISPLAY INVISIBLE (4675 2625);
FORCEPROP 2 LAST SEC 1
J 0
(4675 2625);
PAINT MONO (4675 2625);
DISPLAY INVISIBLE (4675 2625);
FORCEPROP 1 LAST PATH I112
J 0
(4675 2575);
DISPLAY 0.978723 (4675 2575);
PAINT WHITE (4675 2575);
DISPLAY INVISIBLE (4675 2575);
FORCEPROP 2 LAST CDS_LIB mstr_discrete
J 0
(4625 2400);
PAINT ORANGE (4625 2400);
DISPLAY INVISIBLE (4625 2400);
FORCEADD GND..1
(4625 2225);
FORCEPROP 3 LASTPIN (4625 2275) SIG_NAME GND\g
J 0
(4635 2285);
DISPLAY 0.659574 (4635 2285);
PAINT MONO (4635 2285);
DISPLAY INVISIBLE (4635 2285);
FORCEPROP 1 LAST VOLTAGE 0
J 0
(4625 2225);
PAINT SKYBLUE (4625 2225);
DISPLAY INVISIBLE (4625 2225);
FORCEPROP 2 LAST CDS_LIB mstr_symbols
J 0
(4625 2225);
PAINT ORANGE (4625 2225);
DISPLAY INVISIBLE (4625 2225);
FORCEPROP 1 LAST SIZE 1B
J 0
(4700 2175);
DISPLAY 1.723404 (4700 2175);
PAINT GREEN (4700 2175);
DISPLAY INVISIBLE (4700 2175);
FORCEPROP 1 LAST PATH I113
J 0
(4700 2225);
DISPLAY 0.872340 (4700 2225);
PAINT AQUA (4700 2225);
DISPLAY INVISIBLE (4700 2225);
FORCEPROP 2 LAST BOM_COST PROC_VRD_VCCIN_CPU0
J 0
(4250 2300);
DISPLAY 1.446809 (4250 2300);
PAINT MONO (4250 2300);
DISPLAY INVISIBLE (4250 2300);
FORCEPROP 2 LAST ROOM PVCCIN_CPU0_PWR_VR
J 0
(4075 2300);
DISPLAY 1.936170 (4075 2300);
PAINT ORANGE (4075 2300);
DISPLAY INVISIBLE (4075 2300);
FORCEPROP 1 LAST BODY_TYPE PLUMBING
J 0
(4580 2182);
DISPLAY 0.340426 (4580 2182);
PAINT GREEN (4580 2182);
DISPLAY INVISIBLE (4580 2182);
FORCEPROP 1 LAST HDL_POWER GND
J 0
(4625 2375);
DISPLAY 1.723404 (4625 2375);
PAINT GREEN (4625 2375);
DISPLAY INVISIBLE (4625 2375);
FORCEADD RES..2
(4650 25);
FORCEPROP 1 LASTPIN (4650 125) $PN 1
J 0
(4655 87);
DISPLAY 0.787234 (4655 87);
PAINT ORANGE (4655 87);
FORCEPROP 1 LAST PART_NUMBER G21796-187
J 0
(4690 -100);
DISPLAY 0.617021 (4690 -100);
PAINT BLUE (4690 -100);
FORCEPROP 1 LASTPIN (4650 -75) $PN 2
J 0
(4655 -65);
DISPLAY 0.787234 (4655 -65);
PAINT ORANGE (4655 -65);
FORCEPROP 1 LAST VALUE 68.1K
J 0
(4695 100);
DISPLAY 0.617021 (4695 100);
PAINT SKYBLUE (4695 100);
FORCEPROP 1 LAST PACK_TYPE 0402
J 0
(4690 -150);
DISPLAY 0.617021 (4690 -150);
PAINT SKYBLUE (4690 -150);
FORCEPROP 1 LAST LOCATION R1G25
J 0
(4695 150);
DISPLAY 0.617021 (4695 150);
PAINT AQUA (4695 150);
FORCEPROP 0 LAST BOM_SS NOPOP
J 0
(4700 -200);
DISPLAY 0.638298 (4700 -200);
PAINT BROWN (4700 -200);
DISPLAY BOTH (4700 -200);
FORCEPROP 1 LAST TOLERANCE 1%
J 0
(4695 50);
DISPLAY 0.617021 (4695 50);
PAINT SKYBLUE (4695 50);
FORCEPROP 1 LAST WATTAGE 1/16W
J 0
(4690 0);
DISPLAY 0.617021 (4690 0);
PAINT SKYBLUE (4690 0);
FORCEPROP 1 LAST MATERIAL EMPTY
J 0
(4690 -50);
DISPLAY 0.617021 (4690 -50);
PAINT RED (4690 -50);
FORCEPROP 2 LAST SEC_TYPE 0402
J 0
(4700 250);
DISPLAY 1.021277 (4700 250);
PAINT ORANGE (4700 250);
DISPLAY INVISIBLE (4700 250);
FORCEPROP 2 LAST SEC 1
J 0
(4700 250);
PAINT MONO (4700 250);
DISPLAY INVISIBLE (4700 250);
FORCEPROP 1 LAST PATH I114
J 0
(4700 200);
DISPLAY 0.978723 (4700 200);
PAINT WHITE (4700 200);
DISPLAY INVISIBLE (4700 200);
FORCEPROP 2 LAST CDS_LIB mstr_discrete
J 0
(4650 25);
PAINT ORANGE (4650 25);
DISPLAY INVISIBLE (4650 25);
FORCEADD GND..1
(4650 -150);
FORCEPROP 3 LASTPIN (4650 -100) SIG_NAME GND\g
J 0
(4660 -90);
DISPLAY 0.659574 (4660 -90);
PAINT MONO (4660 -90);
DISPLAY INVISIBLE (4660 -90);
FORCEPROP 1 LAST SIZE 1B
J 0
(4725 -200);
DISPLAY 1.723404 (4725 -200);
PAINT GREEN (4725 -200);
DISPLAY INVISIBLE (4725 -200);
FORCEPROP 1 LAST PATH I115
J 0
(4725 -150);
DISPLAY 0.872340 (4725 -150);
PAINT AQUA (4725 -150);
DISPLAY INVISIBLE (4725 -150);
FORCEPROP 1 LAST VOLTAGE 0
J 0
(4650 -150);
PAINT SKYBLUE (4650 -150);
DISPLAY INVISIBLE (4650 -150);
FORCEPROP 2 LAST CDS_LIB mstr_symbols
J 0
(4650 -150);
PAINT ORANGE (4650 -150);
DISPLAY INVISIBLE (4650 -150);
FORCEPROP 2 LAST BOM_COST PROC_VRD_VCCIN_CPU0
J 0
(4275 -75);
DISPLAY 1.446809 (4275 -75);
PAINT MONO (4275 -75);
DISPLAY INVISIBLE (4275 -75);
FORCEPROP 2 LAST ROOM PVCCIN_CPU0_PWR_VR
J 0
(4100 -75);
DISPLAY 1.936170 (4100 -75);
PAINT ORANGE (4100 -75);
DISPLAY INVISIBLE (4100 -75);
FORCEPROP 1 LAST BODY_TYPE PLUMBING
J 0
(4605 -193);
DISPLAY 0.340426 (4605 -193);
PAINT GREEN (4605 -193);
DISPLAY INVISIBLE (4605 -193);
FORCEPROP 1 LAST HDL_POWER GND
J 0
(4650 0);
DISPLAY 1.723404 (4650 0);
PAINT GREEN (4650 0);
DISPLAY INVISIBLE (4650 0);
FORCEADD CAP_A..1
(1050 1725);
FORCEPROP 1 LAST LOCATION CT30
J 0
(900 1675);
DISPLAY 0.617021 (900 1675);
PAINT AQUA (900 1675);
FORCEPROP 1 LAST VOLTAGE 16V
J 0
(1100 1725);
DISPLAY 0.617021 (1100 1725);
PAINT SKYBLUE (1100 1725);
FORCEPROP 1 LAST PART_NUMBER A36096-030
J 0
(1100 1575);
DISPLAY 0.617021 (1100 1575);
PAINT BLUE (1100 1575);
FORCEPROP 1 LAST PACK_TYPE 0402V
J 0
(1100 1525);
DISPLAY 0.617021 (1100 1525);
PAINT SKYBLUE (1100 1525);
FORCEPROP 0 LAST POP NOPOP
J 0
(1095 1449);
DISPLAY 1.021277 (1095 1449);
PAINT RED (1095 1449);
FORCEPROP 1 LASTPIN (1050 1825) $PN 1
J 0
(1060 1805);
DISPLAY 0.787234 (1060 1805);
PAINT ORANGE (1060 1805);
FORCEPROP 1 LASTPIN (1050 1625) $PN 2
J 0
(1060 1605);
DISPLAY 0.787234 (1060 1605);
PAINT ORANGE (1060 1605);
FORCEPROP 1 LAST VALUE 0.1UF
J 0
(1100 1775);
DISPLAY 0.617021 (1100 1775);
PAINT SKYBLUE (1100 1775);
FORCEPROP 1 LAST TOLERANCE 10%
J 0
(1100 1675);
DISPLAY 0.617021 (1100 1675);
PAINT SKYBLUE (1100 1675);
FORCEPROP 1 LAST MATERIAL X7R
J 0
(1100 1625);
DISPLAY 0.617021 (1100 1625);
PAINT SKYBLUE (1100 1625);
FORCEPROP 2 LAST SEC_TYPE 0402V
J 0
(1100 1925);
DISPLAY 1.021277 (1100 1925);
PAINT ORANGE (1100 1925);
DISPLAY INVISIBLE (1100 1925);
FORCEPROP 0 LAST SEC 1
J 0
(1100 1825);
DISPLAY 0.680851 (1100 1825);
PAINT MONO (1100 1825);
DISPLAY INVISIBLE (1100 1825);
FORCEPROP 2 LAST CDS_LIB dev_discrete
J 0
(1050 1725);
PAINT MONO (1050 1725);
DISPLAY INVISIBLE (1050 1725);
FORCEPROP 1 LAST PATH I117
J 0
(1100 1875);
DISPLAY 0.978723 (1100 1875);
PAINT WHITE (1100 1875);
DISPLAY INVISIBLE (1100 1875);
FORCEPROP 2 LAST ROOM PVCCIN_CPU0_PWR_VR
J 0
(1100 1875);
DISPLAY 1.361702 (1100 1875);
PAINT ORANGE (1100 1875);
DISPLAY INVISIBLE (1100 1875);
FORCEADD GND..1
(1050 1475);
FORCEPROP 3 LASTPIN (1050 1525) SIG_NAME GND\g
J 0
(1060 1535);
DISPLAY 0.659574 (1060 1535);
PAINT MONO (1060 1535);
DISPLAY INVISIBLE (1060 1535);
FORCEPROP 2 LAST CDS_LIB mstr_symbols
J 0
(1050 1475);
PAINT MONO (1050 1475);
DISPLAY INVISIBLE (1050 1475);
FORCEPROP 1 LAST PATH I118
J 0
(1125 1475);
DISPLAY 0.872340 (1125 1475);
PAINT AQUA (1125 1475);
DISPLAY INVISIBLE (1125 1475);
FORCEPROP 2 LAST ROOM PVCCIN_CPU0_PWR_VR
J 0
(500 1550);
DISPLAY 1.936170 (500 1550);
PAINT ORANGE (500 1550);
DISPLAY INVISIBLE (500 1550);
FORCEPROP 2 LAST BOM_COST PROC_VRD_VCCIN_CPU0
J 0
(675 1550);
DISPLAY 1.446809 (675 1550);
PAINT MONO (675 1550);
DISPLAY INVISIBLE (675 1550);
FORCEPROP 1 LAST SIZE 1B
J 0
(1125 1425);
DISPLAY 1.723404 (1125 1425);
PAINT GREEN (1125 1425);
DISPLAY INVISIBLE (1125 1425);
FORCEPROP 1 LAST VOLTAGE 0
J 0
(1050 1475);
PAINT SKYBLUE (1050 1475);
DISPLAY INVISIBLE (1050 1475);
FORCEPROP 1 LAST BODY_TYPE PLUMBING
J 0
(1005 1432);
DISPLAY 0.340426 (1005 1432);
PAINT GREEN (1005 1432);
DISPLAY INVISIBLE (1005 1432);
FORCEPROP 1 LAST HDL_POWER GND
J 0
(1050 1625);
DISPLAY 1.723404 (1050 1625);
PAINT GREEN (1050 1625);
DISPLAY INVISIBLE (1050 1625);
FORCEADD GND..1
(2900 1250);
FORCEPROP 3 LASTPIN (2900 1300) SIG_NAME GND\g
J 0
(2910 1310);
DISPLAY 0.659574 (2910 1310);
PAINT MONO (2910 1310);
DISPLAY INVISIBLE (2910 1310);
FORCEPROP 2 LAST CDS_LIB mstr_symbols
J 0
(2900 1250);
PAINT MONO (2900 1250);
DISPLAY INVISIBLE (2900 1250);
FORCEPROP 1 LAST PATH I120
J 0
(2975 1250);
DISPLAY 0.872340 (2975 1250);
PAINT AQUA (2975 1250);
DISPLAY INVISIBLE (2975 1250);
FORCEPROP 2 LAST ROOM PVCCIN_CPU0_PWR_VR
J 0
(2350 1325);
DISPLAY 1.936170 (2350 1325);
PAINT ORANGE (2350 1325);
DISPLAY INVISIBLE (2350 1325);
FORCEPROP 2 LAST BOM_COST PROC_VRD_VCCIN_CPU0
J 0
(2525 1325);
DISPLAY 1.446809 (2525 1325);
PAINT MONO (2525 1325);
DISPLAY INVISIBLE (2525 1325);
FORCEPROP 1 LAST VOLTAGE 0
J 0
(2900 1250);
PAINT SKYBLUE (2900 1250);
DISPLAY INVISIBLE (2900 1250);
FORCEPROP 1 LAST SIZE 1B
J 0
(2975 1200);
DISPLAY 1.723404 (2975 1200);
PAINT GREEN (2975 1200);
DISPLAY INVISIBLE (2975 1200);
FORCEPROP 1 LAST BODY_TYPE PLUMBING
J 0
(2855 1207);
DISPLAY 0.340426 (2855 1207);
PAINT GREEN (2855 1207);
DISPLAY INVISIBLE (2855 1207);
FORCEPROP 1 LAST HDL_POWER GND
J 0
(2900 1400);
DISPLAY 1.723404 (2900 1400);
PAINT GREEN (2900 1400);
DISPLAY INVISIBLE (2900 1400);
FORCEADD CAP..1
(2950 2225);
FORCEPROP 1 LAST PACK_TYPE 0402LF
J 0
(3000 2025);
DISPLAY 0.617021 (3000 2025);
PAINT SKYBLUE (3000 2025);
FORCEPROP 1 LASTPIN (2950 2125) $PN 2
J 0
(2960 2105);
DISPLAY 0.787234 (2960 2105);
PAINT ORANGE (2960 2105);
FORCEPROP 1 LASTPIN (2950 2325) $PN 1
J 0
(2960 2305);
DISPLAY 0.787234 (2960 2305);
PAINT ORANGE (2960 2305);
FORCEPROP 1 LAST VOLTAGE 50V
J 0
(3000 2225);
DISPLAY 0.617021 (3000 2225);
PAINT SKYBLUE (3000 2225);
FORCEPROP 1 LAST MATERIAL X7R
J 0
(3000 2125);
DISPLAY 0.617021 (3000 2125);
PAINT SKYBLUE (3000 2125);
FORCEPROP 1 LAST TOLERANCE 10%
J 0
(3000 2175);
DISPLAY 0.617021 (3000 2175);
PAINT SKYBLUE (3000 2175);
FORCEPROP 1 LAST PART_NUMBER A36096-046
J 0
(3000 2075);
DISPLAY 0.617021 (3000 2075);
PAINT BLUE (3000 2075);
FORCEPROP 1 LAST LOCATION CT28
J 0
(2800 2225);
DISPLAY 0.617021 (2800 2225);
PAINT AQUA (2800 2225);
FORCEPROP 0 LAST POP NOPOP
J 0
(2700 2300);
DISPLAY 1.021277 (2700 2300);
PAINT RED (2700 2300);
FORCEPROP 1 LAST VALUE 1000PF
J 0
(3000 2275);
DISPLAY 0.617021 (3000 2275);
PAINT SKYBLUE (3000 2275);
FORCEPROP 2 LAST SEC_TYPE 0402LF
J 0
(3000 2425);
DISPLAY 1.021277 (3000 2425);
PAINT ORANGE (3000 2425);
DISPLAY INVISIBLE (3000 2425);
FORCEPROP 0 LAST SEC 1
J 0
(2700 2350);
DISPLAY 0.680851 (2700 2350);
PAINT MONO (2700 2350);
DISPLAY INVISIBLE (2700 2350);
FORCEPROP 2 LAST CDS_LIB mstr_discrete
J 0
(2950 2225);
PAINT MONO (2950 2225);
DISPLAY INVISIBLE (2950 2225);
FORCEPROP 1 LAST PATH I122
J 0
(3000 2375);
DISPLAY 0.978723 (3000 2375);
PAINT WHITE (3000 2375);
DISPLAY INVISIBLE (3000 2375);
FORCEPROP 0 LAST ROOM VDDQ_KLM_PWR_VR
J 0
(3000 2425);
DISPLAY 1.021277 (3000 2425);
PAINT ORANGE (3000 2425);
DISPLAY INVISIBLE (3000 2425);
FORCEADD GND..1
(2950 2025);
FORCEPROP 3 LASTPIN (2950 2075) SIG_NAME GND\g
J 0
(2960 2085);
DISPLAY 0.659574 (2960 2085);
PAINT MONO (2960 2085);
DISPLAY INVISIBLE (2960 2085);
FORCEPROP 2 LAST CDS_LIB mstr_symbols
J 0
(2950 2025);
PAINT MONO (2950 2025);
DISPLAY INVISIBLE (2950 2025);
FORCEPROP 1 LAST PATH I123
J 0
(3025 2025);
DISPLAY 0.872340 (3025 2025);
PAINT AQUA (3025 2025);
DISPLAY INVISIBLE (3025 2025);
FORCEPROP 2 LAST ROOM VDDQ_KLM_PWR_VR
J 0
(2375 2100);
DISPLAY 1.361702 (2375 2100);
PAINT ORANGE (2375 2100);
DISPLAY INVISIBLE (2375 2100);
FORCEPROP 1 LAST VOLTAGE 0
J 0
(2950 2025);
PAINT SKYBLUE (2950 2025);
DISPLAY INVISIBLE (2950 2025);
FORCEPROP 1 LAST SIZE 1B
J 0
(3025 1975);
DISPLAY 1.170213 (3025 1975);
PAINT AQUA (3025 1975);
DISPLAY INVISIBLE (3025 1975);
FORCEPROP 1 LAST BODY_TYPE PLUMBING
J 0
(2905 1982);
DISPLAY 0.340426 (2905 1982);
PAINT GREEN (2905 1982);
DISPLAY INVISIBLE (2905 1982);
FORCEPROP 1 LAST HDL_POWER GND
J 0
(2950 2175);
DISPLAY 1.170213 (2950 2175);
PAINT GREEN (2950 2175);
DISPLAY INVISIBLE (2950 2175);
FORCEADD CAP_A..1
(1150 -625);
FORCEPROP 0 LAST BOM_SS NOPOP
J 0
(1250 -950);
DISPLAY 0.638298 (1250 -950);
PAINT BROWN (1250 -950);
DISPLAY BOTH (1250 -950);
FORCEPROP 1 LASTPIN (1150 -525) $PN 1
J 0
(1160 -545);
DISPLAY 0.787234 (1160 -545);
PAINT ORANGE (1160 -545);
FORCEPROP 1 LAST VOLTAGE 16V
J 0
(1200 -625);
DISPLAY 0.617021 (1200 -625);
PAINT SKYBLUE (1200 -625);
FORCEPROP 1 LAST LOCATION CT31
J 0
(1000 -625);
DISPLAY 0.617021 (1000 -625);
PAINT AQUA (1000 -625);
FORCEPROP 1 LAST PART_NUMBER A36096-030
J 0
(1200 -775);
DISPLAY 0.617021 (1200 -775);
PAINT BLUE (1200 -775);
FORCEPROP 1 LAST PACK_TYPE 0402V
J 0
(1200 -825);
DISPLAY 0.617021 (1200 -825);
PAINT SKYBLUE (1200 -825);
FORCEPROP 0 LAST POP NOPOP
J 0
(1208 -893);
DISPLAY 1.021277 (1208 -893);
PAINT RED (1208 -893);
FORCEPROP 1 LASTPIN (1150 -725) $PN 2
J 0
(1160 -745);
DISPLAY 0.787234 (1160 -745);
PAINT ORANGE (1160 -745);
FORCEPROP 1 LAST MATERIAL X7R
J 0
(1200 -725);
DISPLAY 0.617021 (1200 -725);
PAINT SKYBLUE (1200 -725);
FORCEPROP 1 LAST TOLERANCE 10%
J 0
(1200 -675);
DISPLAY 0.617021 (1200 -675);
PAINT SKYBLUE (1200 -675);
FORCEPROP 1 LAST VALUE 0.1UF
J 0
(1200 -575);
DISPLAY 0.617021 (1200 -575);
PAINT SKYBLUE (1200 -575);
FORCEPROP 2 LAST SEC_TYPE 0402V
J 0
(1200 -425);
DISPLAY 1.021277 (1200 -425);
PAINT ORANGE (1200 -425);
DISPLAY INVISIBLE (1200 -425);
FORCEPROP 0 LAST SEC 1
J 0
(1200 -525);
DISPLAY 0.680851 (1200 -525);
PAINT MONO (1200 -525);
DISPLAY INVISIBLE (1200 -525);
FORCEPROP 2 LAST CDS_LIB dev_discrete
J 0
(1150 -625);
PAINT MONO (1150 -625);
DISPLAY INVISIBLE (1150 -625);
FORCEPROP 1 LAST PATH I124
J 0
(1200 -475);
DISPLAY 0.978723 (1200 -475);
PAINT WHITE (1200 -475);
DISPLAY INVISIBLE (1200 -475);
FORCEPROP 2 LAST ROOM PVCCIN_CPU0_PWR_VR
J 0
(1200 -475);
DISPLAY 1.361702 (1200 -475);
PAINT ORANGE (1200 -475);
DISPLAY INVISIBLE (1200 -475);
FORCEADD GND..1
(1150 -875);
FORCEPROP 3 LASTPIN (1150 -825) SIG_NAME GND\g
J 0
(1160 -815);
DISPLAY 0.659574 (1160 -815);
PAINT MONO (1160 -815);
DISPLAY INVISIBLE (1160 -815);
FORCEPROP 2 LAST ROOM PVCCIN_CPU0_PWR_VR
J 0
(600 -800);
DISPLAY 1.936170 (600 -800);
PAINT ORANGE (600 -800);
DISPLAY INVISIBLE (600 -800);
FORCEPROP 2 LAST BOM_COST PROC_VRD_VCCIN_CPU0
J 0
(775 -800);
DISPLAY 1.446809 (775 -800);
PAINT MONO (775 -800);
DISPLAY INVISIBLE (775 -800);
FORCEPROP 1 LAST SIZE 1B
J 0
(1225 -925);
DISPLAY 1.723404 (1225 -925);
PAINT GREEN (1225 -925);
DISPLAY INVISIBLE (1225 -925);
FORCEPROP 1 LAST VOLTAGE 0
J 0
(1150 -875);
PAINT SKYBLUE (1150 -875);
DISPLAY INVISIBLE (1150 -875);
FORCEPROP 1 LAST PATH I125
J 0
(1225 -875);
DISPLAY 0.872340 (1225 -875);
PAINT AQUA (1225 -875);
DISPLAY INVISIBLE (1225 -875);
FORCEPROP 2 LAST CDS_LIB mstr_symbols
J 0
(1150 -875);
PAINT MONO (1150 -875);
DISPLAY INVISIBLE (1150 -875);
FORCEPROP 1 LAST BODY_TYPE PLUMBING
J 0
(1105 -918);
DISPLAY 0.340426 (1105 -918);
PAINT GREEN (1105 -918);
DISPLAY INVISIBLE (1105 -918);
FORCEPROP 1 LAST HDL_POWER GND
J 0
(1150 -725);
DISPLAY 1.723404 (1150 -725);
PAINT GREEN (1150 -725);
DISPLAY INVISIBLE (1150 -725);
FORCEADD GND..1
(3250 -1100);
FORCEPROP 3 LASTPIN (3250 -1050) SIG_NAME GND\g
J 0
(3260 -1040);
DISPLAY 0.659574 (3260 -1040);
PAINT MONO (3260 -1040);
DISPLAY INVISIBLE (3260 -1040);
FORCEPROP 2 LAST CDS_LIB mstr_symbols
J 0
(3250 -1100);
PAINT MONO (3250 -1100);
DISPLAY INVISIBLE (3250 -1100);
FORCEPROP 1 LAST PATH I128
J 0
(3325 -1100);
DISPLAY 0.872340 (3325 -1100);
PAINT AQUA (3325 -1100);
DISPLAY INVISIBLE (3325 -1100);
FORCEPROP 2 LAST ROOM PVCCIN_CPU0_PWR_VR
J 0
(2700 -1025);
DISPLAY 1.936170 (2700 -1025);
PAINT ORANGE (2700 -1025);
DISPLAY INVISIBLE (2700 -1025);
FORCEPROP 2 LAST BOM_COST PROC_VRD_VCCIN_CPU0
J 0
(2875 -1025);
DISPLAY 1.446809 (2875 -1025);
PAINT MONO (2875 -1025);
DISPLAY INVISIBLE (2875 -1025);
FORCEPROP 1 LAST VOLTAGE 0
J 0
(3250 -1100);
PAINT SKYBLUE (3250 -1100);
DISPLAY INVISIBLE (3250 -1100);
FORCEPROP 1 LAST SIZE 1B
J 0
(3325 -1150);
DISPLAY 1.723404 (3325 -1150);
PAINT GREEN (3325 -1150);
DISPLAY INVISIBLE (3325 -1150);
FORCEPROP 1 LAST BODY_TYPE PLUMBING
J 0
(3205 -1143);
DISPLAY 0.340426 (3205 -1143);
PAINT GREEN (3205 -1143);
DISPLAY INVISIBLE (3205 -1143);
FORCEPROP 1 LAST HDL_POWER GND
J 0
(3250 -950);
DISPLAY 1.723404 (3250 -950);
PAINT GREEN (3250 -950);
DISPLAY INVISIBLE (3250 -950);
FORCEADD CAP..1
(3050 -75);
FORCEPROP 1 LAST TOLERANCE 10%
J 0
(3100 -125);
DISPLAY 0.617021 (3100 -125);
PAINT SKYBLUE (3100 -125);
FORCEPROP 1 LASTPIN (3050 -175) $PN 2
J 0
(3060 -195);
DISPLAY 0.787234 (3060 -195);
PAINT ORANGE (3060 -195);
FORCEPROP 1 LASTPIN (3050 25) $PN 1
J 0
(3060 5);
DISPLAY 0.787234 (3060 5);
PAINT ORANGE (3060 5);
FORCEPROP 1 LAST PACK_TYPE 0402LF
J 0
(3100 -275);
DISPLAY 0.617021 (3100 -275);
PAINT SKYBLUE (3100 -275);
FORCEPROP 1 LAST PART_NUMBER A36096-046
J 0
(3100 -225);
DISPLAY 0.617021 (3100 -225);
PAINT BLUE (3100 -225);
FORCEPROP 1 LAST MATERIAL X7R
J 0
(3100 -175);
DISPLAY 0.617021 (3100 -175);
PAINT SKYBLUE (3100 -175);
FORCEPROP 0 LAST BOM_SS NOPOP
J 0
(3100 -325);
DISPLAY 0.638298 (3100 -325);
PAINT BROWN (3100 -325);
DISPLAY BOTH (3100 -325);
FORCEPROP 1 LAST VOLTAGE 50V
J 0
(3100 -75);
DISPLAY 0.617021 (3100 -75);
PAINT SKYBLUE (3100 -75);
FORCEPROP 1 LAST LOCATION CT32
J 0
(2900 -75);
DISPLAY 0.617021 (2900 -75);
PAINT AQUA (2900 -75);
FORCEPROP 1 LAST VALUE 1000PF
J 0
(3100 -25);
DISPLAY 0.617021 (3100 -25);
PAINT SKYBLUE (3100 -25);
FORCEPROP 0 LAST POP NOPOP
J 0
(2825 -25);
DISPLAY 1.021277 (2825 -25);
PAINT RED (2825 -25);
FORCEPROP 2 LAST SEC_TYPE 0402LF
J 0
(3100 125);
DISPLAY 1.021277 (3100 125);
PAINT ORANGE (3100 125);
DISPLAY INVISIBLE (3100 125);
FORCEPROP 0 LAST SEC 1
J 0
(3100 25);
DISPLAY 0.680851 (3100 25);
PAINT MONO (3100 25);
DISPLAY INVISIBLE (3100 25);
FORCEPROP 2 LAST CDS_LIB mstr_discrete
J 0
(3050 -75);
PAINT MONO (3050 -75);
DISPLAY INVISIBLE (3050 -75);
FORCEPROP 1 LAST PATH I130
J 0
(3100 75);
DISPLAY 0.978723 (3100 75);
PAINT WHITE (3100 75);
DISPLAY INVISIBLE (3100 75);
FORCEPROP 0 LAST ROOM VDDQ_KLM_PWR_VR
J 0
(3100 125);
DISPLAY 1.021277 (3100 125);
PAINT ORANGE (3100 125);
DISPLAY INVISIBLE (3100 125);
FORCEADD GND..1
(3050 -300);
FORCEPROP 3 LASTPIN (3050 -250) SIG_NAME GND\g
J 0
(3060 -240);
DISPLAY 0.659574 (3060 -240);
PAINT MONO (3060 -240);
DISPLAY INVISIBLE (3060 -240);
FORCEPROP 2 LAST CDS_LIB mstr_symbols
J 0
(3050 -300);
PAINT MONO (3050 -300);
DISPLAY INVISIBLE (3050 -300);
FORCEPROP 1 LAST PATH I131
J 0
(3125 -300);
DISPLAY 0.872340 (3125 -300);
PAINT AQUA (3125 -300);
DISPLAY INVISIBLE (3125 -300);
FORCEPROP 2 LAST ROOM VDDQ_KLM_PWR_VR
J 0
(2475 -225);
DISPLAY 1.361702 (2475 -225);
PAINT ORANGE (2475 -225);
DISPLAY INVISIBLE (2475 -225);
FORCEPROP 1 LAST VOLTAGE 0
J 0
(3050 -300);
PAINT SKYBLUE (3050 -300);
DISPLAY INVISIBLE (3050 -300);
FORCEPROP 1 LAST SIZE 1B
J 0
(3125 -350);
DISPLAY 1.170213 (3125 -350);
PAINT AQUA (3125 -350);
DISPLAY INVISIBLE (3125 -350);
FORCEPROP 1 LAST BODY_TYPE PLUMBING
J 0
(3005 -343);
DISPLAY 0.340426 (3005 -343);
PAINT GREEN (3005 -343);
DISPLAY INVISIBLE (3005 -343);
FORCEPROP 1 LAST HDL_POWER GND
J 0
(3050 -150);
DISPLAY 1.170213 (3050 -150);
PAINT GREEN (3050 -150);
DISPLAY INVISIBLE (3050 -150);
FORCEADD CAP..1
(2900 1800);
FORCEPROP 0 LAST POP NOPOP
J 0
(2975 1750);
DISPLAY 0.808511 (2975 1750);
PAINT RED (2975 1750);
FORCEPROP 1 LAST PART_NUMBER A36096-046
J 0
(3150 1800);
DISPLAY 0.617021 (3150 1800);
PAINT BLUE (3150 1800);
FORCEPROP 1 LAST MATERIAL X7R
J 0
(3050 1800);
DISPLAY 0.617021 (3050 1800);
PAINT SKYBLUE (3050 1800);
FORCEPROP 1 LASTPIN (2900 1700) $PN 2
J 0
(2910 1680);
DISPLAY 0.787234 (2910 1680);
PAINT ORANGE (2910 1680);
FORCEPROP 1 LASTPIN (2900 1900) $PN 1
J 0
(2910 1880);
DISPLAY 0.787234 (2910 1880);
PAINT ORANGE (2910 1880);
FORCEPROP 1 LAST VOLTAGE 50V
J 0
(2950 1800);
DISPLAY 0.617021 (2950 1800);
PAINT SKYBLUE (2950 1800);
FORCEPROP 1 LAST PACK_TYPE 0402LF
J 0
(3325 1850);
DISPLAY 0.617021 (3325 1850);
PAINT SKYBLUE (3325 1850);
FORCEPROP 1 LAST TOLERANCE 10%
J 0
(3200 1850);
DISPLAY 0.617021 (3200 1850);
PAINT SKYBLUE (3200 1850);
FORCEPROP 1 LAST VALUE 1000PF
J 0
(3050 1850);
DISPLAY 0.617021 (3050 1850);
PAINT SKYBLUE (3050 1850);
FORCEPROP 1 LAST LOCATION CT29
J 0
(2950 1850);
DISPLAY 0.617021 (2950 1850);
PAINT AQUA (2950 1850);
FORCEPROP 2 LAST SEC_TYPE 0402LF
J 0
(2950 2000);
DISPLAY 1.021277 (2950 2000);
PAINT ORANGE (2950 2000);
DISPLAY INVISIBLE (2950 2000);
FORCEPROP 0 LAST SEC 1
J 0
(2950 1950);
DISPLAY 0.680851 (2950 1950);
PAINT MONO (2950 1950);
DISPLAY INVISIBLE (2950 1950);
FORCEPROP 0 LAST ROOM VDDQ_KLM_PWR_VR
J 0
(2950 2000);
DISPLAY 1.021277 (2950 2000);
PAINT ORANGE (2950 2000);
DISPLAY INVISIBLE (2950 2000);
FORCEPROP 1 LAST PATH I140
J 0
(2950 1950);
DISPLAY 0.978723 (2950 1950);
PAINT WHITE (2950 1950);
DISPLAY INVISIBLE (2950 1950);
FORCEPROP 2 LAST CDS_LIB mstr_discrete
J 0
(2900 1800);
PAINT MONO (2900 1800);
DISPLAY INVISIBLE (2900 1800);
FORCEADD CAP..1
(3250 -625);
FORCEPROP 1 LAST PACK_TYPE 0402LF
J 0
(3400 -725);
DISPLAY 0.617021 (3400 -725);
PAINT SKYBLUE (3400 -725);
FORCEPROP 1 LASTPIN (3250 -525) $PN 1
J 0
(3260 -545);
DISPLAY 0.787234 (3260 -545);
PAINT ORANGE (3260 -545);
FORCEPROP 1 LASTPIN (3250 -725) $PN 2
J 0
(3260 -745);
DISPLAY 0.787234 (3260 -745);
PAINT ORANGE (3260 -745);
FORCEPROP 1 LAST MATERIAL X7R
J 0
(3300 -725);
DISPLAY 0.617021 (3300 -725);
PAINT SKYBLUE (3300 -725);
FORCEPROP 1 LAST TOLERANCE 10%
J 0
(3300 -675);
DISPLAY 0.617021 (3300 -675);
PAINT SKYBLUE (3300 -675);
FORCEPROP 1 LAST VOLTAGE 50V
J 0
(3300 -625);
DISPLAY 0.617021 (3300 -625);
PAINT SKYBLUE (3300 -625);
FORCEPROP 1 LAST VALUE 1000PF
J 0
(3300 -575);
DISPLAY 0.617021 (3300 -575);
PAINT SKYBLUE (3300 -575);
FORCEPROP 1 LAST PART_NUMBER A36096-046
J 0
(3300 -775);
DISPLAY 0.617021 (3300 -775);
PAINT BLUE (3300 -775);
FORCEPROP 1 LAST LOCATION CT33
J 0
(3300 -525);
DISPLAY 0.617021 (3300 -525);
PAINT AQUA (3300 -525);
FORCEPROP 0 LAST POP NOPOP
J 0
(3050 -600);
DISPLAY 0.808511 (3050 -600);
PAINT RED (3050 -600);
FORCEPROP 0 LAST BOM_SS NOPOP
J 0
(2925 -675);
DISPLAY 0.638298 (2925 -675);
PAINT BROWN (2925 -675);
DISPLAY BOTH (2925 -675);
FORCEPROP 2 LAST SEC_TYPE 0402LF
J 0
(3300 -425);
DISPLAY 1.021277 (3300 -425);
PAINT ORANGE (3300 -425);
DISPLAY INVISIBLE (3300 -425);
FORCEPROP 0 LAST SEC 1
J 0
(3300 -475);
DISPLAY 0.680851 (3300 -475);
PAINT MONO (3300 -475);
DISPLAY INVISIBLE (3300 -475);
FORCEPROP 2 LAST CDS_LIB mstr_discrete
J 0
(3250 -625);
PAINT MONO (3250 -625);
DISPLAY INVISIBLE (3250 -625);
FORCEPROP 1 LAST PATH I141
J 0
(3300 -475);
DISPLAY 0.978723 (3300 -475);
PAINT WHITE (3300 -475);
DISPLAY INVISIBLE (3300 -475);
FORCEPROP 0 LAST ROOM VDDQ_KLM_PWR_VR
J 0
(3300 -425);
DISPLAY 1.021277 (3300 -425);
PAINT ORANGE (3300 -425);
DISPLAY INVISIBLE (3300 -425);
FORCEADD RES..1
(100 2000);
FORCEPROP 1 LASTPIN (0 2000) $PN 1
J 0
(12 2012);
DISPLAY 0.787234 (12 2012);
PAINT ORANGE (12 2012);
FORCEPROP 1 LAST PACK_TYPE 0603
J 0
(175 1950);
DISPLAY 0.617021 (175 1950);
PAINT SKYBLUE (175 1950);
FORCEPROP 1 LAST MATERIAL CHIP
J 0
(100 1850);
DISPLAY 0.617021 (100 1850);
PAINT SKYBLUE (100 1850);
FORCEPROP 1 LAST LOCATION RT19
J 0
(100 2075);
DISPLAY 0.617021 (100 2075);
PAINT AQUA (100 2075);
FORCEPROP 1 LAST VALUE 0
J 2
(50 1950);
DISPLAY 0.617021 (50 1950);
PAINT SKYBLUE (50 1950);
FORCEPROP 1 LASTPIN (200 2000) $PN 2
J 0
(162 2012);
DISPLAY 0.787234 (162 2012);
PAINT ORANGE (162 2012);
FORCEPROP 1 LAST WATTAGE 1/10W
J 2
(75 1850);
DISPLAY 0.617021 (75 1850);
PAINT SKYBLUE (75 1850);
FORCEPROP 1 LAST TOLERANCE 5.0%
J 0
(100 1900);
DISPLAY 0.617021 (100 1900);
PAINT SKYBLUE (100 1900);
FORCEPROP 1 LAST PART_NUMBER G22178-002
J 0
(-150 2050);
DISPLAY 0.617021 (-150 2050);
PAINT BLUE (-150 2050);
FORCEPROP 2 LAST SEC_TYPE 0603
J 0
(50 2200);
DISPLAY 1.021277 (50 2200);
PAINT ORANGE (50 2200);
DISPLAY INVISIBLE (50 2200);
FORCEPROP 0 LAST SEC 1
J 0
(-150 2100);
DISPLAY 0.680851 (-150 2100);
PAINT MONO (-150 2100);
DISPLAY INVISIBLE (-150 2100);
FORCEPROP 0 LAST ROOM NIC_SPRV
J 0
(200 2125);
DISPLAY 1.021277 (200 2125);
PAINT ORANGE (200 2125);
DISPLAY INVISIBLE (200 2125);
FORCEPROP 0 LAST BOM_COST NT_GBE_BASE
J 0
(200 2225);
DISPLAY 1.021277 (200 2225);
PAINT ORANGE (200 2225);
DISPLAY INVISIBLE (200 2225);
FORCEPROP 1 LAST PATH I144
J 0
(50 2150);
DISPLAY 0.978723 (50 2150);
PAINT WHITE (50 2150);
DISPLAY INVISIBLE (50 2150);
FORCEPROP 2 LAST CDS_LIB mstr_discrete
J 0
(100 2000);
PAINT MONO (100 2000);
DISPLAY INVISIBLE (100 2000);
FORCEADD RES..1
(275 -325);
FORCEPROP 1 LASTPIN (175 -325) $PN 1
J 0
(187 -313);
DISPLAY 0.787234 (187 -313);
PAINT ORANGE (187 -313);
FORCEPROP 0 LAST BOM_SS NOPOP
J 0
(500 -475);
DISPLAY 0.638298 (500 -475);
PAINT BROWN (500 -475);
DISPLAY BOTH (500 -475);
FORCEPROP 1 LAST VALUE 0
J 2
(225 -375);
DISPLAY 0.617021 (225 -375);
PAINT SKYBLUE (225 -375);
FORCEPROP 1 LAST WATTAGE 1/10W
J 2
(625 -425);
DISPLAY 0.617021 (625 -425);
PAINT SKYBLUE (625 -425);
FORCEPROP 1 LASTPIN (375 -325) $PN 2
J 0
(337 -313);
DISPLAY 0.787234 (337 -313);
PAINT ORANGE (337 -313);
FORCEPROP 1 LAST PACK_TYPE 0603
J 0
(200 -425);
DISPLAY 0.617021 (200 -425);
PAINT SKYBLUE (200 -425);
FORCEPROP 1 LAST TOLERANCE 5.0%
J 0
(325 -425);
DISPLAY 0.617021 (325 -425);
PAINT SKYBLUE (325 -425);
FORCEPROP 1 LAST PART_NUMBER G22178-002
J 0
(175 -475);
DISPLAY 0.617021 (175 -475);
PAINT BLUE (175 -475);
FORCEPROP 1 LAST MATERIAL CHIP
J 0
(500 -375);
DISPLAY 0.617021 (500 -375);
PAINT SKYBLUE (500 -375);
FORCEPROP 1 LAST LOCATION RT21
J 0
(325 -375);
DISPLAY 0.617021 (325 -375);
PAINT AQUA (325 -375);
FORCEPROP 2 LAST SEC_TYPE 0603
J 0
(225 -125);
DISPLAY 1.021277 (225 -125);
PAINT ORANGE (225 -125);
DISPLAY INVISIBLE (225 -125);
FORCEPROP 0 LAST SEC 1
J 0
(25 -225);
DISPLAY 0.680851 (25 -225);
PAINT MONO (25 -225);
DISPLAY INVISIBLE (25 -225);
FORCEPROP 2 LAST CDS_LIB mstr_discrete
J 0
(275 -325);
PAINT MONO (275 -325);
DISPLAY INVISIBLE (275 -325);
FORCEPROP 1 LAST PATH I145
J 0
(225 -175);
DISPLAY 0.978723 (225 -175);
PAINT WHITE (225 -175);
DISPLAY INVISIBLE (225 -175);
FORCEPROP 0 LAST BOM_COST NT_GBE_BASE
J 0
(375 -100);
DISPLAY 1.021277 (375 -100);
PAINT ORANGE (375 -100);
DISPLAY INVISIBLE (375 -100);
FORCEPROP 0 LAST ROOM NIC_SPRV
J 0
(375 -200);
DISPLAY 1.021277 (375 -200);
PAINT ORANGE (375 -200);
DISPLAY INVISIBLE (375 -200);
FORCEADD RES..1
(-700 3050);
FORCEPROP 1 LASTPIN (-800 3050) $PN 1
J 0
(-788 3062);
DISPLAY 0.617021 (-788 3062);
PAINT WHITE (-788 3062);
FORCEPROP 1 LASTPIN (-600 3050) $PN 2
J 0
(-638 3062);
DISPLAY 0.617021 (-638 3062);
PAINT WHITE (-638 3062);
FORCEPROP 1 LAST LOCATION R9U1
J 0
(-800 3100);
DISPLAY 0.617021 (-800 3100);
PAINT AQUA (-800 3100);
FORCEPROP 1 LAST TOLERANCE 5%
J 0
(-750 2950);
DISPLAY 0.617021 (-750 2950);
PAINT SKYBLUE (-750 2950);
FORCEPROP 1 LAST PACK_TYPE 0402
J 0
(-625 2950);
DISPLAY 0.617021 (-625 2950);
PAINT SKYBLUE (-625 2950);
FORCEPROP 1 LAST WATTAGE 1/16W
J 2
(-350 3100);
DISPLAY 0.510638 (-350 3100);
PAINT SKYBLUE (-350 3100);
FORCEPROP 1 LAST VALUE 0.0
J 2
(-800 2950);
DISPLAY 0.617021 (-800 2950);
PAINT SKYBLUE (-800 2950);
FORCEPROP 1 LAST MATERIAL CHIP
J 0
(-475 2950);
DISPLAY 0.510638 (-475 2950);
PAINT SKYBLUE (-475 2950);
FORCEPROP 1 LAST PART_NUMBER G21497-005
J 0
(-825 3000);
DISPLAY 0.617021 (-825 3000);
PAINT BLUE (-825 3000);
FORCEPROP 2 LAST CDS_LOCATION R9U1
J 0
(-1175 3050);
DISPLAY 0.617021 (-1175 3050);
PAINT AQUA (-1175 3050);
DISPLAY INVISIBLE (-1175 3050);
FORCEPROP 1 LAST PATH I150
J 0
(-750 3200);
DISPLAY 0.978723 (-750 3200);
PAINT WHITE (-750 3200);
DISPLAY INVISIBLE (-750 3200);
FORCEPROP 0 LAST CDS_SEC 1
J 0
(-400 3100);
PAINT MONO (-400 3100);
DISPLAY INVISIBLE (-400 3100);
FORCEPROP 2 LAST ROOM CPU0
J 0
(-750 3200);
PAINT PEACH (-750 3200);
DISPLAY INVISIBLE (-750 3200);
FORCEPROP 2 LAST SEC 1
J 0
(-750 3275);
DISPLAY 0.680851 (-750 3275);
PAINT MONO (-750 3275);
DISPLAY INVISIBLE (-750 3275);
FORCEPROP 2 LAST SEC_TYPE 0402
J 0
(-750 3275);
DISPLAY 1.021277 (-750 3275);
PAINT ORANGE (-750 3275);
DISPLAY INVISIBLE (-750 3275);
FORCEPROP 2 LAST CDS_LIB mstr_discrete
J 0
(-700 3050);
DISPLAY 1.340426 (-700 3050);
PAINT ORANGE (-700 3050);
DISPLAY INVISIBLE (-700 3050);
FORCEPROP 2 LAST BOM_COST PROC_SIDEBAND
J 0
(-700 3050);
PAINT MONO (-700 3050);
DISPLAY INVISIBLE (-700 3050);
FORCEADD RES..1
(-550 675);
FORCEPROP 1 LAST PART_NUMBER G21497-005
J 0
(-675 625);
DISPLAY 0.617021 (-675 625);
PAINT BLUE (-675 625);
FORCEPROP 1 LAST PACK_TYPE 0402
J 0
(-475 575);
DISPLAY 0.617021 (-475 575);
PAINT SKYBLUE (-475 575);
FORCEPROP 1 LASTPIN (-650 675) $PN 1
J 0
(-638 687);
DISPLAY 0.617021 (-638 687);
PAINT WHITE (-638 687);
FORCEPROP 1 LAST VALUE 0.0
J 2
(-650 575);
DISPLAY 0.617021 (-650 575);
PAINT SKYBLUE (-650 575);
FORCEPROP 1 LAST TOLERANCE 5%
J 0
(-600 575);
DISPLAY 0.617021 (-600 575);
PAINT SKYBLUE (-600 575);
FORCEPROP 1 LASTPIN (-450 675) $PN 2
J 0
(-488 687);
DISPLAY 0.617021 (-488 687);
PAINT WHITE (-488 687);
FORCEPROP 1 LAST LOCATION R9U12
J 0
(-650 725);
DISPLAY 0.617021 (-650 725);
PAINT AQUA (-650 725);
FORCEPROP 0 LAST BOM_SS NOPOP
J 0
(-200 725);
DISPLAY 0.638298 (-200 725);
PAINT BROWN (-200 725);
DISPLAY BOTH (-200 725);
FORCEPROP 1 LAST MATERIAL CHIP
J 0
(-325 575);
DISPLAY 0.510638 (-325 575);
PAINT SKYBLUE (-325 575);
FORCEPROP 1 LAST WATTAGE 1/16W
J 2
(-225 725);
DISPLAY 0.510638 (-225 725);
PAINT SKYBLUE (-225 725);
FORCEPROP 2 LAST CDS_LOCATION R9U12
J 0
(-1025 675);
DISPLAY 0.617021 (-1025 675);
PAINT AQUA (-1025 675);
DISPLAY INVISIBLE (-1025 675);
FORCEPROP 0 LAST CDS_SEC 1
J 0
(-250 725);
PAINT MONO (-250 725);
DISPLAY INVISIBLE (-250 725);
FORCEPROP 2 LAST ROOM CPU0
J 0
(-600 825);
PAINT PEACH (-600 825);
DISPLAY INVISIBLE (-600 825);
FORCEPROP 2 LAST SEC 1
J 0
(-600 900);
DISPLAY 0.680851 (-600 900);
PAINT MONO (-600 900);
DISPLAY INVISIBLE (-600 900);
FORCEPROP 2 LAST SEC_TYPE 0402
J 0
(-600 900);
DISPLAY 1.021277 (-600 900);
PAINT ORANGE (-600 900);
DISPLAY INVISIBLE (-600 900);
FORCEPROP 2 LAST CDS_LIB mstr_discrete
J 0
(-550 675);
DISPLAY 1.340426 (-550 675);
PAINT ORANGE (-550 675);
DISPLAY INVISIBLE (-550 675);
FORCEPROP 2 LAST BOM_COST PROC_SIDEBAND
J 0
(-550 675);
PAINT MONO (-550 675);
DISPLAY INVISIBLE (-550 675);
FORCEPROP 1 LAST PATH I151
J 0
(-600 825);
DISPLAY 0.978723 (-600 825);
PAINT WHITE (-600 825);
DISPLAY INVISIBLE (-600 825);
FORCEADD SC1U10V2KX-4-GP..1
(-250 150);
FORCEPROP 0 LAST BOM_SS NOPOP
J 0
(-100 -25);
DISPLAY 0.638298 (-100 -25);
PAINT BROWN (-100 -25);
DISPLAY BOTH (-100 -25);
FORCEPROP 2 LASTPIN (-250 225) $PN 1
R 1
J 0
(-260 235);
DISPLAY 0.808511 (-260 235);
PAINT ORANGE (-260 235);
FORCEPROP 2 LASTPIN (-250 75) $PN 2
R 1
J 2
(-260 65);
DISPLAY 0.808511 (-260 65);
PAINT ORANGE (-260 65);
FORCEPROP 2 LAST PACK_SIZE 0402
J 0
(-125 25);
DISPLAY 0.638298 (-125 25);
PAINT GREEN (-125 25);
FORCEPROP 1 LAST VALUE SC1U10V2KX-4-GP
R 1
J 0
(-150 -75);
DISPLAY 0.617021 (-150 -75);
PAINT GREEN (-150 -75);
FORCEPROP 2 LAST RATED 10V
J 0
(-125 75);
DISPLAY 0.638298 (-125 75);
PAINT GREEN (-125 75);
FORCEPROP 2 LAST TOLERANCE 10%
J 0
(-125 125);
DISPLAY 0.638298 (-125 125);
PAINT GREEN (-125 125);
FORCEPROP 2 LAST ATTRIBUTE 1UF
J 0
(-125 175);
DISPLAY 0.638298 (-125 175);
PAINT GREEN (-125 175);
FORCEPROP 1 LAST LOCATION C1F21
J 0
(-125 230);
DISPLAY 0.617021 (-125 230);
PAINT GREEN (-125 230);
FORCEPROP 1 LAST PACK_TYPE SMD-BCG6
J 0
(-250 150);
DISPLAY 0.617021 (-250 150);
PAINT GREEN (-250 150);
DISPLAY INVISIBLE (-250 150);
FORCEPROP 2 LAST SEC 1
J 0
(-225 225);
DISPLAY 0.680851 (-225 225);
PAINT MONO (-225 225);
DISPLAY INVISIBLE (-225 225);
FORCEPROP 2 LAST SEC_TYPE SMD-BCG6
J 0
(-225 225);
DISPLAY 1.021277 (-225 225);
PAINT ORANGE (-225 225);
DISPLAY INVISIBLE (-225 225);
FORCEPROP 1 LAST PART_NUMBER 78.10523.8FL
J 0
(-250 150);
DISPLAY 0.617021 (-250 150);
PAINT GREEN (-250 150);
DISPLAY INVISIBLE (-250 150);
FORCEPROP 2 LAST CDS_LIB w_hdl
J 0
(-250 150);
PAINT MONO (-250 150);
DISPLAY INVISIBLE (-250 150);
FORCEPROP 1 LAST PATH I154
J 0
(-250 150);
DISPLAY 0.617021 (-250 150);
PAINT GREEN (-250 150);
DISPLAY INVISIBLE (-250 150);
FORCEPROP 1 LAST CDS_LMAN_SYM_OUTLINE -50,25,50,-25
J 0
(-250 150);
DISPLAY 0.468085 (-250 150);
PAINT GREEN (-250 150);
DISPLAY INVISIBLE (-250 150);
FORCEADD SC1U10V2KX-4-GP..1
(-375 2500);
FORCEPROP 2 LAST PACK_SIZE 0402
J 0
(-250 2375);
DISPLAY 0.638298 (-250 2375);
PAINT GREEN (-250 2375);
FORCEPROP 2 LAST RATED 10V
J 0
(-250 2425);
DISPLAY 0.638298 (-250 2425);
PAINT GREEN (-250 2425);
FORCEPROP 2 LAST TOLERANCE 10%
J 0
(-250 2475);
DISPLAY 0.638298 (-250 2475);
PAINT GREEN (-250 2475);
FORCEPROP 2 LAST ATTRIBUTE 1UF
J 0
(-250 2525);
DISPLAY 0.638298 (-250 2525);
PAINT GREEN (-250 2525);
FORCEPROP 2 LASTPIN (-375 2575) $PN 1
R 1
J 0
(-385 2585);
DISPLAY 0.808511 (-385 2585);
PAINT ORANGE (-385 2585);
FORCEPROP 1 LAST VALUE SC1U10V2KX-4-GP
R 1
J 0
(-275 2275);
DISPLAY 0.617021 (-275 2275);
PAINT GREEN (-275 2275);
FORCEPROP 1 LAST LOCATION C1G4
J 0
(-250 2580);
DISPLAY 0.617021 (-250 2580);
PAINT GREEN (-250 2580);
FORCEPROP 2 LASTPIN (-375 2425) $PN 2
R 1
J 2
(-385 2415);
DISPLAY 0.808511 (-385 2415);
PAINT ORANGE (-385 2415);
FORCEPROP 1 LAST PACK_TYPE SMD-BCG6
J 0
(-375 2500);
DISPLAY 0.617021 (-375 2500);
PAINT GREEN (-375 2500);
DISPLAY INVISIBLE (-375 2500);
FORCEPROP 2 LAST SEC 1
J 0
(-350 2575);
DISPLAY 0.680851 (-350 2575);
PAINT MONO (-350 2575);
DISPLAY INVISIBLE (-350 2575);
FORCEPROP 2 LAST SEC_TYPE SMD-BCG6
J 0
(-350 2575);
DISPLAY 1.021277 (-350 2575);
PAINT ORANGE (-350 2575);
DISPLAY INVISIBLE (-350 2575);
FORCEPROP 1 LAST CDS_LMAN_SYM_OUTLINE -50,25,50,-25
J 0
(-375 2500);
DISPLAY 0.468085 (-375 2500);
PAINT GREEN (-375 2500);
DISPLAY INVISIBLE (-375 2500);
FORCEPROP 1 LAST PATH I155
J 0
(-375 2500);
DISPLAY 0.617021 (-375 2500);
PAINT GREEN (-375 2500);
DISPLAY INVISIBLE (-375 2500);
FORCEPROP 2 LAST CDS_LIB w_hdl
J 0
(-375 2500);
PAINT MONO (-375 2500);
DISPLAY INVISIBLE (-375 2500);
FORCEPROP 1 LAST PART_NUMBER 78.10523.8FL
J 0
(-375 2500);
DISPLAY 0.617021 (-375 2500);
PAINT GREEN (-375 2500);
DISPLAY INVISIBLE (-375 2500);
FORCEADD 1R3F-GP..1
(2900 1475);
FORCEPROP 2 LASTPIN (2900 1600) $PN 1
R 1
J 0
(2890 1610);
DISPLAY 0.808511 (2890 1610);
PAINT ORANGE (2890 1610);
FORCEPROP 2 LASTPIN (2900 1350) $PN 2
R 1
J 2
(2890 1340);
DISPLAY 0.808511 (2890 1340);
PAINT ORANGE (2890 1340);
FORCEPROP 2 LAST TOLERANCE 1%
J 0
(2950 1450);
DISPLAY 0.638298 (2950 1450);
PAINT GREEN (2950 1450);
FORCEPROP 2 LAST ATTRIBUTE 1 OHM
J 0
(2950 1500);
DISPLAY 0.638298 (2950 1500);
PAINT GREEN (2950 1500);
FORCEPROP 1 LAST VALUE 1R3F-GP
J 0
(2950 1550);
DISPLAY 0.617021 (2950 1550);
PAINT GREEN (2950 1550);
FORCEPROP 1 LAST LOCATION RT20
J 0
(2950 1600);
DISPLAY 0.617021 (2950 1600);
PAINT GREEN (2950 1600);
FORCEPROP 2 LAST RATED 1/10W
J 0
(2950 1400);
DISPLAY 0.638298 (2950 1400);
PAINT GREEN (2950 1400);
FORCEPROP 2 LAST PACK_SIZE 0603
J 0
(2950 1350);
DISPLAY 0.638298 (2950 1350);
PAINT GREEN (2950 1350);
FORCEPROP 0 LAST POP NOPOP
J 0
(2950 1300);
DISPLAY 0.638298 (2950 1300);
PAINT RED (2950 1300);
FORCEPROP 1 LAST PATH I156
J 0
(2900 1475);
DISPLAY 0.617021 (2900 1475);
PAINT GREEN (2900 1475);
DISPLAY INVISIBLE (2900 1475);
FORCEPROP 1 LAST CDS_LMAN_SYM_OUTLINE -50,75,50,-75
J 0
(2900 1475);
DISPLAY 0.468085 (2900 1475);
PAINT GREEN (2900 1475);
DISPLAY INVISIBLE (2900 1475);
FORCEPROP 2 LAST CDS_LIB w_hdl
J 0
(2900 1475);
DISPLAY INVISIBLE (2900 1475);
FORCEPROP 1 LAST PART_NUMBER 64.1R005.55L
J 0
(2900 1475);
DISPLAY 0.617021 (2900 1475);
PAINT GREEN (2900 1475);
DISPLAY INVISIBLE (2900 1475);
FORCEPROP 2 LAST SEC_TYPE RCL_GP
J 0
(2950 1575);
DISPLAY 1.021277 (2950 1575);
PAINT ORANGE (2950 1575);
DISPLAY INVISIBLE (2950 1575);
FORCEPROP 2 LAST SEC 1
J 0
(2950 1575);
DISPLAY 0.680851 (2950 1575);
PAINT MONO (2950 1575);
DISPLAY INVISIBLE (2950 1575);
FORCEPROP 1 LAST PACK_TYPE RCL_GP
J 0
(2900 1475);
DISPLAY 0.617021 (2900 1475);
PAINT GREEN (2900 1475);
DISPLAY INVISIBLE (2900 1475);
FORCEADD 1R3F-GP..1
(3250 -925);
FORCEPROP 2 LAST TOLERANCE 1%
J 0
(3300 -950);
DISPLAY 0.638298 (3300 -950);
PAINT GREEN (3300 -950);
FORCEPROP 2 LAST ATTRIBUTE 1 OHM
J 0
(3300 -900);
DISPLAY 0.638298 (3300 -900);
PAINT GREEN (3300 -900);
FORCEPROP 2 LASTPIN (3250 -1050) $PN 2
R 1
J 2
(3240 -1060);
DISPLAY 0.808511 (3240 -1060);
PAINT ORANGE (3240 -1060);
FORCEPROP 2 LASTPIN (3250 -800) $PN 1
R 1
J 0
(3240 -790);
DISPLAY 0.808511 (3240 -790);
PAINT ORANGE (3240 -790);
FORCEPROP 1 LAST VALUE 1R3F-GP
J 0
(3300 -850);
DISPLAY 0.617021 (3300 -850);
PAINT GREEN (3300 -850);
FORCEPROP 1 LAST LOCATION RT22
J 0
(3300 -800);
DISPLAY 0.617021 (3300 -800);
PAINT GREEN (3300 -800);
FORCEPROP 2 LAST RATED 1/10W
J 0
(3300 -1000);
DISPLAY 0.638298 (3300 -1000);
PAINT GREEN (3300 -1000);
FORCEPROP 0 LAST BOM_SS NOPOP
J 0
(2900 -975);
DISPLAY 0.638298 (2900 -975);
PAINT BROWN (2900 -975);
DISPLAY BOTH (2900 -975);
FORCEPROP 2 LAST PACK_SIZE 0603
J 0
(3300 -1050);
DISPLAY 0.638298 (3300 -1050);
PAINT GREEN (3300 -1050);
FORCEPROP 0 LAST POP NOPOP
J 0
(3300 -1100);
DISPLAY 0.638298 (3300 -1100);
PAINT RED (3300 -1100);
FORCEPROP 1 LAST CDS_LMAN_SYM_OUTLINE -50,75,50,-75
J 0
(3250 -925);
DISPLAY 0.468085 (3250 -925);
PAINT GREEN (3250 -925);
DISPLAY INVISIBLE (3250 -925);
FORCEPROP 2 LAST CDS_LIB w_hdl
J 0
(3250 -925);
DISPLAY INVISIBLE (3250 -925);
FORCEPROP 1 LAST PART_NUMBER 64.1R005.55L
J 0
(3250 -925);
DISPLAY 0.617021 (3250 -925);
PAINT GREEN (3250 -925);
DISPLAY INVISIBLE (3250 -925);
FORCEPROP 2 LAST SEC_TYPE RCL_GP
J 0
(3300 -825);
DISPLAY 1.021277 (3300 -825);
PAINT ORANGE (3300 -825);
DISPLAY INVISIBLE (3300 -825);
FORCEPROP 2 LAST SEC 1
J 0
(3300 -825);
DISPLAY 0.680851 (3300 -825);
PAINT MONO (3300 -825);
DISPLAY INVISIBLE (3300 -825);
FORCEPROP 1 LAST PACK_TYPE RCL_GP
J 0
(3250 -925);
DISPLAY 0.617021 (3250 -925);
PAINT GREEN (3250 -925);
DISPLAY INVISIBLE (3250 -925);
FORCEPROP 1 LAST PATH I157
J 0
(3250 -925);
DISPLAY 0.617021 (3250 -925);
PAINT GREEN (3250 -925);
DISPLAY INVISIBLE (3250 -925);
FORCEADD IND-120NH-30-GP..1
R 1
(3950 1975);
FORCEPROP 1 LAST LOCATION L1G1
J 0
(3800 2025);
DISPLAY 0.617021 (3800 2025);
PAINT GREEN (3800 2025);
FORCEPROP 0 LAST NEW_RATED DS_ISAT=134A@25C
J 0
(3750 1625);
DISPLAY 0.638298 (3750 1625);
PAINT BROWN (3750 1625);
FORCEPROP 0 LAST DS_VALUE 90NH
J 0
(3750 1675);
DISPLAY 0.638298 (3750 1675);
PAINT BROWN (3750 1675);
DISPLAY BOTH (3750 1675);
FORCEPROP 0 LAST BOM_DS 068.9002N.1021
J 0
(3750 1725);
DISPLAY 0.638298 (3750 1725);
PAINT BROWN (3750 1725);
DISPLAY BOTH (3750 1725);
FORCEPROP 0 LAST SS_ISAT 94A@25C
J 0
(3750 1775);
DISPLAY 0.638298 (3750 1775);
PAINT BROWN (3750 1775);
DISPLAY BOTH (3750 1775);
FORCEPROP 0 LAST SS_VALUE 120NH
J 0
(3750 1825);
DISPLAY 0.638298 (3750 1825);
PAINT BROWN (3750 1825);
DISPLAY BOTH (3750 1825);
FORCEPROP 0 LAST BOM_SS 068.1202N.M001
J 0
(3750 1875);
DISPLAY 0.638298 (3750 1875);
PAINT BROWN (3750 1875);
DISPLAY BOTH (3750 1875);
FORCEPROP 0 LAST NEW_PACK_SIZE DCR=0.17MOHM
J 0
(3750 1525);
DISPLAY 0.638298 (3750 1525);
PAINT BROWN (3750 1525);
FORCEPROP 0 LAST NEW_TYPE IRMS=66A@DELTA_T<40C
J 0
(3750 1575);
DISPLAY 0.638298 (3750 1575);
PAINT BROWN (3750 1575);
FORCEPROP 2 LASTPIN (3800 1950) $PN 1
J 2
(3790 1960);
DISPLAY 0.808511 (3790 1960);
PAINT ORANGE (3790 1960);
FORCEPROP 2 LASTPIN (4100 1950) $PN 2
J 0
(4110 1960);
DISPLAY 0.808511 (4110 1960);
PAINT ORANGE (4110 1960);
FORCEPROP 1 LAST PATH I160
R 1
J 0
(3950 1975);
DISPLAY 0.617021 (3950 1975);
PAINT GREEN (3950 1975);
DISPLAY INVISIBLE (3950 1975);
FORCEPROP 1 LAST PART_NUMBER 068.1202N.M001
R 1
J 0
(3950 1975);
DISPLAY 0.617021 (3950 1975);
PAINT GREEN (3950 1975);
DISPLAY INVISIBLE (3950 1975);
FORCEPROP 2 LAST CDS_LIB w_hdl
R 1
J 0
(3950 1975);
PAINT MONO (3950 1975);
DISPLAY INVISIBLE (3950 1975);
FORCEPROP 1 LAST CDS_LMAN_SYM_OUTLINE -75,100,75,-100
R 1
J 0
(3950 1975);
DISPLAY 0.468085 (3950 1975);
PAINT GREEN (3950 1975);
DISPLAY INVISIBLE (3950 1975);
FORCEPROP 2 LAST SEC_TYPE DISCRET-GB2
J 0
(3825 2050);
DISPLAY 1.021277 (3825 2050);
PAINT ORANGE (3825 2050);
DISPLAY INVISIBLE (3825 2050);
FORCEPROP 2 LAST SEC 1
J 0
(3825 2050);
DISPLAY 0.680851 (3825 2050);
PAINT MONO (3825 2050);
DISPLAY INVISIBLE (3825 2050);
FORCEPROP 1 LAST PACK_TYPE DISCRET-GB2
R 1
J 0
(3950 1975);
DISPLAY 0.617021 (3950 1975);
PAINT GREEN (3950 1975);
DISPLAY INVISIBLE (3950 1975);
FORCEPROP 1 LAST VALUE IND-120NH-30-GP
J 0
(3800 1875);
DISPLAY 0.617021 (3800 1875);
PAINT GREEN (3800 1875);
DISPLAY INVISIBLE (3800 1875);
FORCEPROP 0 LAST ATTRIBUTE 120NH
J 0
(3800 1825);
DISPLAY 0.638298 (3800 1825);
PAINT GREEN (3800 1825);
DISPLAY INVISIBLE (3800 1825);
FORCEPROP 0 LAST RATED ISAT=94A@25C
J 0
(3800 1775);
DISPLAY 0.638298 (3800 1775);
PAINT GREEN (3800 1775);
DISPLAY INVISIBLE (3800 1775);
FORCEPROP 0 LAST PACK_SIZE DCR=0.17MOHM
J 0
(3800 1675);
DISPLAY 0.638298 (3800 1675);
PAINT GREEN (3800 1675);
DISPLAY INVISIBLE (3800 1675);
FORCEPROP 0 LAST TYPE IRMS=66A@DELTA_T<40C
J 0
(3800 1725);
DISPLAY 0.638298 (3800 1725);
PAINT GREEN (3800 1725);
DISPLAY INVISIBLE (3800 1725);
FORCEADD IND-120NH-30-GP..1
R 1
(3900 -400);
FORCEPROP 1 LAST LOCATION L1F2
J 0
(3750 -350);
DISPLAY 0.617021 (3750 -350);
PAINT GREEN (3750 -350);
FORCEPROP 2 LASTPIN (3750 -425) $PN 1
J 2
(3740 -415);
DISPLAY 0.808511 (3740 -415);
PAINT ORANGE (3740 -415);
FORCEPROP 0 LAST NEW_PACK_SIZE DCR=0.17MOHM
J 0
(3700 -750);
DISPLAY 0.638298 (3700 -750);
PAINT BROWN (3700 -750);
FORCEPROP 0 LAST NEW_TYPE IRMS=66A@DELTA_T<40C
J 0
(3700 -700);
DISPLAY 0.638298 (3700 -700);
PAINT BROWN (3700 -700);
FORCEPROP 0 LAST DS_VALUE 90NH
J 0
(3700 -600);
DISPLAY 0.638298 (3700 -600);
PAINT BROWN (3700 -600);
DISPLAY BOTH (3700 -600);
FORCEPROP 0 LAST BOM_DS 068.9002N.1021
J 0
(3700 -550);
DISPLAY 0.638298 (3700 -550);
PAINT BROWN (3700 -550);
DISPLAY BOTH (3700 -550);
FORCEPROP 2 LASTPIN (4050 -425) $PN 2
J 0
(4060 -415);
DISPLAY 0.808511 (4060 -415);
PAINT ORANGE (4060 -415);
FORCEPROP 0 LAST BOM_SS NOPOP
J 0
(3700 -500);
DISPLAY 0.638298 (3700 -500);
PAINT BROWN (3700 -500);
DISPLAY BOTH (3700 -500);
FORCEPROP 0 LAST NEW_RATED DS_ISAT=134A@25C
J 0
(3700 -650);
DISPLAY 0.638298 (3700 -650);
PAINT BROWN (3700 -650);
FORCEPROP 1 LAST PART_NUMBER 068.1202N.M001
R 1
J 0
(3900 -400);
DISPLAY 0.617021 (3900 -400);
PAINT GREEN (3900 -400);
DISPLAY INVISIBLE (3900 -400);
FORCEPROP 2 LAST CDS_LIB w_hdl
R 1
J 0
(3900 -400);
PAINT MONO (3900 -400);
DISPLAY INVISIBLE (3900 -400);
FORCEPROP 1 LAST CDS_LMAN_SYM_OUTLINE -75,100,75,-100
R 1
J 0
(3900 -400);
DISPLAY 0.468085 (3900 -400);
PAINT GREEN (3900 -400);
DISPLAY INVISIBLE (3900 -400);
FORCEPROP 2 LAST SEC_TYPE DISCRET-GB2
J 0
(3775 -325);
DISPLAY 1.021277 (3775 -325);
PAINT ORANGE (3775 -325);
DISPLAY INVISIBLE (3775 -325);
FORCEPROP 2 LAST SEC 1
J 0
(3775 -325);
DISPLAY 0.680851 (3775 -325);
PAINT MONO (3775 -325);
DISPLAY INVISIBLE (3775 -325);
FORCEPROP 1 LAST PACK_TYPE DISCRET-GB2
R 1
J 0
(3900 -400);
DISPLAY 0.617021 (3900 -400);
PAINT GREEN (3900 -400);
DISPLAY INVISIBLE (3900 -400);
FORCEPROP 1 LAST VALUE IND-120NH-30-GP
J 0
(3750 -500);
DISPLAY 0.617021 (3750 -500);
PAINT GREEN (3750 -500);
DISPLAY INVISIBLE (3750 -500);
FORCEPROP 0 LAST ATTRIBUTE 120NH
J 0
(3750 -550);
DISPLAY 0.638298 (3750 -550);
PAINT GREEN (3750 -550);
DISPLAY INVISIBLE (3750 -550);
FORCEPROP 0 LAST RATED ISAT=94A@25C
J 0
(3750 -600);
DISPLAY 0.638298 (3750 -600);
PAINT GREEN (3750 -600);
DISPLAY INVISIBLE (3750 -600);
FORCEPROP 0 LAST PACK_SIZE DCR=0.17MOHM
J 0
(3750 -700);
DISPLAY 0.638298 (3750 -700);
PAINT GREEN (3750 -700);
DISPLAY INVISIBLE (3750 -700);
FORCEPROP 0 LAST TYPE IRMS=66A@DELTA_T<40C
J 0
(3750 -650);
DISPLAY 0.638298 (3750 -650);
PAINT GREEN (3750 -650);
DISPLAY INVISIBLE (3750 -650);
FORCEPROP 1 LAST PATH I161
R 1
J 0
(3900 -400);
DISPLAY 0.617021 (3900 -400);
PAINT GREEN (3900 -400);
DISPLAY INVISIBLE (3900 -400);
FORCEADD GND..1
(2675 1500);
FORCEPROP 3 LASTPIN (2675 1550) SIG_NAME GND\g
J 0
(2685 1560);
DISPLAY 0.659574 (2685 1560);
PAINT MONO (2685 1560);
DISPLAY INVISIBLE (2685 1560);
FORCEPROP 1 LAST PATH I19
J 0
(2750 1500);
DISPLAY 0.893617 (2750 1500);
PAINT AQUA (2750 1500);
DISPLAY INVISIBLE (2750 1500);
FORCEPROP 2 LAST CDS_LIB mstr_symbols
J 0
(2675 1500);
DISPLAY 1.936170 (2675 1500);
PAINT ORANGE (2675 1500);
DISPLAY INVISIBLE (2675 1500);
FORCEPROP 1 LAST VOLTAGE 0
J 0
(2675 1500);
PAINT SKYBLUE (2675 1500);
DISPLAY INVISIBLE (2675 1500);
FORCEPROP 1 LAST SIZE 1B
J 0
(2750 1450);
DISPLAY 1.723404 (2750 1450);
PAINT GREEN (2750 1450);
DISPLAY INVISIBLE (2750 1450);
FORCEPROP 2 LAST BOM_COST VDDQ_GHJ_PWR_VR
J 0
(2300 1575);
DISPLAY 1.446809 (2300 1575);
PAINT MONO (2300 1575);
DISPLAY INVISIBLE (2300 1575);
FORCEPROP 2 LAST ROOM VDDQ_GHJ_PWR_VR
J 0
(2125 1575);
DISPLAY 1.936170 (2125 1575);
PAINT ORANGE (2125 1575);
DISPLAY INVISIBLE (2125 1575);
FORCEPROP 1 LAST BODY_TYPE PLUMBING
J 0
(2630 1457);
DISPLAY 0.340426 (2630 1457);
PAINT GREEN (2630 1457);
DISPLAY INVISIBLE (2630 1457);
FORCEPROP 1 LAST HDL_POWER GND
J 0
(2675 1650);
DISPLAY 1.723404 (2675 1650);
PAINT GREEN (2675 1650);
DISPLAY INVISIBLE (2675 1650);
FORCEADD OFFPAGE..2
(3675 2800);
FORCEPROP 2 LAST $XR0 223 
J 0
(3864 2800);
DISPLAY 0.638298 (3864 2800);
PAINT MONO (3864 2800);
FORCEPROP 2 LAST BOM_COST VDDQ_GHJ_PWR_VR
J 0
(3875 2850);
DISPLAY 1.446809 (3875 2850);
PAINT MONO (3875 2850);
DISPLAY INVISIBLE (3875 2850);
FORCEPROP 2 LAST PATH I3
J 0
(3865 2850);
DISPLAY 1.021277 (3865 2850);
PAINT ORANGE (3865 2850);
DISPLAY INVISIBLE (3865 2850);
FORCEPROP 2 LAST CDS_LIB mstr_standard
J 0
(3675 2800);
DISPLAY 1.936170 (3675 2800);
PAINT ORANGE (3675 2800);
DISPLAY INVISIBLE (3675 2800);
FORCEPROP 2 LAST ROOM VDDQ_GHJ_PWR_VR
J 0
(3275 2875);
DISPLAY 1.936170 (3275 2875);
PAINT ORANGE (3275 2875);
DISPLAY INVISIBLE (3275 2875);
FORCEPROP 1 LAST OFFPAGE TRUE
J 0
(4000 2675);
DISPLAY 1.723404 (4000 2675);
PAINT GREEN (4000 2675);
DISPLAY INVISIBLE (4000 2675);
FORCEPROP 1 LAST COMMENT_BODY TRUE
J 0
(3630 2705);
DISPLAY 1.723404 (3630 2705);
PAINT GREEN (3630 2705);
DISPLAY INVISIBLE (3630 2705);
FORCEADD OFFPAGE..1
(-1575 2150);
FORCEPROP 2 LASTPIN (-1525 2150) SIG_NAME VR_PVDDQ_GHJ_PWM1
J 0
(-1510 2160);
DISPLAY 0.617021 (-1510 2160);
PAINT ORANGE (-1510 2160);
FORCEPROP 2 LAST $XR0 223 
J 0
(-1827 2150);
DISPLAY 0.638298 (-1827 2150);
PAINT MONO (-1827 2150);
FORCEPROP 2 LAST PATH I33
J 0
(-1855 2200);
DISPLAY 1.021277 (-1855 2200);
PAINT ORANGE (-1855 2200);
DISPLAY INVISIBLE (-1855 2200);
FORCEPROP 2 LAST ROOM VDDQ_GHJ_PWR_VR
J 0
(-1975 2225);
DISPLAY 1.936170 (-1975 2225);
PAINT ORANGE (-1975 2225);
DISPLAY INVISIBLE (-1975 2225);
FORCEPROP 2 LAST BOM_COST VDDQ_GHJ_PWR_VR
J 0
(-1825 2200);
DISPLAY 1.446809 (-1825 2200);
PAINT MONO (-1825 2200);
DISPLAY INVISIBLE (-1825 2200);
FORCEPROP 2 LAST CDS_LIB mstr_standard
J 0
(-1575 2150);
DISPLAY 1.936170 (-1575 2150);
PAINT ORANGE (-1575 2150);
DISPLAY INVISIBLE (-1575 2150);
FORCEPROP 1 LAST OFFPAGE TRUE
J 0
(-1250 2025);
DISPLAY 1.680851 (-1250 2025);
PAINT GREEN (-1250 2025);
DISPLAY INVISIBLE (-1250 2025);
FORCEPROP 1 LAST COMMENT_BODY TRUE
J 0
(-1450 2050);
DISPLAY 1.680851 (-1450 2050);
PAINT GREEN (-1450 2050);
DISPLAY INVISIBLE (-1450 2050);
FORCEADD GND..1
(-1950 2025);
FORCEPROP 3 LASTPIN (-1950 2075) SIG_NAME GND\g
J 0
(-1940 2085);
DISPLAY 0.659574 (-1940 2085);
PAINT MONO (-1940 2085);
DISPLAY INVISIBLE (-1940 2085);
FORCEPROP 1 LAST PATH I35
J 0
(-1875 2025);
DISPLAY 0.893617 (-1875 2025);
PAINT AQUA (-1875 2025);
DISPLAY INVISIBLE (-1875 2025);
FORCEPROP 2 LAST CDS_LIB mstr_symbols
J 0
(-1950 2025);
DISPLAY 1.936170 (-1950 2025);
PAINT ORANGE (-1950 2025);
DISPLAY INVISIBLE (-1950 2025);
FORCEPROP 1 LAST VOLTAGE 0
J 0
(-1950 2025);
PAINT SKYBLUE (-1950 2025);
DISPLAY INVISIBLE (-1950 2025);
FORCEPROP 2 LAST BOM_COST VDDQ_GHJ_PWR_VR
J 0
(-2325 2100);
DISPLAY 1.446809 (-2325 2100);
PAINT MONO (-2325 2100);
DISPLAY INVISIBLE (-2325 2100);
FORCEPROP 2 LAST ROOM VDDQ_GHJ_PWR_VR
J 0
(-2500 2100);
DISPLAY 1.936170 (-2500 2100);
PAINT ORANGE (-2500 2100);
DISPLAY INVISIBLE (-2500 2100);
FORCEPROP 1 LAST SIZE 1B
J 0
(-1875 1975);
DISPLAY 1.723404 (-1875 1975);
PAINT GREEN (-1875 1975);
DISPLAY INVISIBLE (-1875 1975);
FORCEPROP 1 LAST BODY_TYPE PLUMBING
J 0
(-1995 1982);
DISPLAY 0.340426 (-1995 1982);
PAINT GREEN (-1995 1982);
DISPLAY INVISIBLE (-1995 1982);
FORCEPROP 1 LAST HDL_POWER GND
J 0
(-1950 2175);
DISPLAY 1.723404 (-1950 2175);
PAINT GREEN (-1950 2175);
DISPLAY INVISIBLE (-1950 2175);
FORCEADD OFFPAGE..2
(3750 3150);
FORCEPROP 2 LAST $XR0 223 
J 0
(3939 3150);
DISPLAY 0.638298 (3939 3150);
PAINT MONO (3939 3150);
FORCEPROP 2 LAST BOM_COST VDDQ_GHJ_PWR_VR
J 0
(3950 3200);
DISPLAY 1.446809 (3950 3200);
PAINT MONO (3950 3200);
DISPLAY INVISIBLE (3950 3200);
FORCEPROP 2 LAST PATH I4
J 0
(3940 3200);
DISPLAY 1.021277 (3940 3200);
PAINT ORANGE (3940 3200);
DISPLAY INVISIBLE (3940 3200);
FORCEPROP 2 LAST CDS_LIB mstr_standard
J 2
(3750 3150);
DISPLAY 1.936170 (3750 3150);
PAINT ORANGE (3750 3150);
DISPLAY INVISIBLE (3750 3150);
FORCEPROP 2 LAST ROOM VDDQ_GHJ_PWR_VR
J 0
(3350 3225);
DISPLAY 1.936170 (3350 3225);
PAINT ORANGE (3350 3225);
DISPLAY INVISIBLE (3350 3225);
FORCEPROP 1 LAST OFFPAGE TRUE
J 0
(4075 3025);
DISPLAY 1.723404 (4075 3025);
PAINT GREEN (4075 3025);
DISPLAY INVISIBLE (4075 3025);
FORCEPROP 1 LAST COMMENT_BODY TRUE
J 0
(3705 3055);
DISPLAY 1.723404 (3705 3055);
PAINT GREEN (3705 3055);
DISPLAY INVISIBLE (3705 3055);
FORCEADD CAP..1
R 2
(-775 1900);
FORCEPROP 1 LASTPIN (-775 1800) $PN 2
J 2
(-785 1780);
DISPLAY 0.617021 (-785 1780);
PAINT ORANGE (-785 1780);
FORCEPROP 1 LAST PART_NUMBER A36096-104
J 2
(-825 1750);
DISPLAY 0.617021 (-825 1750);
PAINT BLUE (-825 1750);
FORCEPROP 1 LAST MATERIAL X7R
J 2
(-825 1800);
DISPLAY 0.617021 (-825 1800);
PAINT SKYBLUE (-825 1800);
FORCEPROP 1 LAST TOLERANCE 10%
J 2
(-825 1850);
DISPLAY 0.617021 (-825 1850);
PAINT SKYBLUE (-825 1850);
FORCEPROP 1 LAST PACK_TYPE 0402
J 2
(-825 1700);
DISPLAY 0.617021 (-825 1700);
PAINT SKYBLUE (-825 1700);
FORCEPROP 1 LASTPIN (-775 2000) $PN 1
J 2
(-785 1980);
DISPLAY 0.617021 (-785 1980);
PAINT ORANGE (-785 1980);
FORCEPROP 1 LAST VOLTAGE 16V
J 2
(-825 1900);
DISPLAY 0.617021 (-825 1900);
PAINT SKYBLUE (-825 1900);
FORCEPROP 1 LAST VALUE 0.220UF
J 2
(-825 1950);
DISPLAY 0.617021 (-825 1950);
PAINT SKYBLUE (-825 1950);
FORCEPROP 1 LAST LOCATION C1G11
J 2
(-825 2000);
DISPLAY 0.617021 (-825 2000);
PAINT AQUA (-825 2000);
FORCEPROP 2 LAST ROOM VDDQ_GHJ_PWR_VR
J 0
(-850 2050);
DISPLAY 1.361702 (-850 2050);
PAINT ORANGE (-850 2050);
DISPLAY INVISIBLE (-850 2050);
FORCEPROP 1 LAST PATH I44
J 2
(-825 2050);
DISPLAY 0.978723 (-825 2050);
PAINT WHITE (-825 2050);
DISPLAY INVISIBLE (-825 2050);
FORCEPROP 2 LAST CDS_LOCATION C1G11
J 2
(-825 2000);
DISPLAY 0.617021 (-825 2000);
PAINT AQUA (-825 2000);
DISPLAY INVISIBLE (-825 2000);
FORCEPROP 2 LAST SEC 1
J 0
(-825 2100);
DISPLAY 0.680851 (-825 2100);
PAINT MONO (-825 2100);
DISPLAY INVISIBLE (-825 2100);
FORCEPROP 2 LAST SEC_TYPE 0402
J 0
(-825 2100);
DISPLAY 1.021277 (-825 2100);
PAINT ORANGE (-825 2100);
DISPLAY INVISIBLE (-825 2100);
FORCEPROP 0 LAST SPOF TRUE
J 0
(-825 2100);
DISPLAY 1.021277 (-825 2100);
PAINT ORANGE (-825 2100);
DISPLAY INVISIBLE (-825 2100);
FORCEPROP 2 LAST CDS_LIB mstr_discrete
J 0
(-775 1900);
PAINT ORANGE (-775 1900);
DISPLAY INVISIBLE (-775 1900);
FORCEADD CAP..1
(-2150 2500);
FORCEPROP 1 LAST TOLERANCE 10%
J 0
(-2100 2450);
DISPLAY 0.617021 (-2100 2450);
PAINT SKYBLUE (-2100 2450);
FORCEPROP 1 LAST MATERIAL X6S
J 0
(-2100 2400);
DISPLAY 0.617021 (-2100 2400);
PAINT SKYBLUE (-2100 2400);
FORCEPROP 1 LAST PART_NUMBER C95333-007
J 0
(-2100 2350);
DISPLAY 0.617021 (-2100 2350);
PAINT BLUE (-2100 2350);
FORCEPROP 1 LAST LOCATION C9U6
J 0
(-2100 2600);
DISPLAY 0.617021 (-2100 2600);
PAINT AQUA (-2100 2600);
FORCEPROP 1 LAST VALUE 10UF
J 0
(-2100 2550);
DISPLAY 0.617021 (-2100 2550);
PAINT SKYBLUE (-2100 2550);
FORCEPROP 1 LAST PACK_TYPE 0805
J 0
(-2100 2300);
DISPLAY 0.617021 (-2100 2300);
PAINT SKYBLUE (-2100 2300);
FORCEPROP 1 LASTPIN (-2150 2400) $PN 2
J 0
(-2140 2380);
DISPLAY 0.617021 (-2140 2380);
PAINT ORANGE (-2140 2380);
FORCEPROP 1 LAST VOLTAGE 16V
J 0
(-2100 2500);
DISPLAY 0.617021 (-2100 2500);
PAINT SKYBLUE (-2100 2500);
FORCEPROP 1 LASTPIN (-2150 2600) $PN 1
J 0
(-2140 2580);
DISPLAY 0.617021 (-2140 2580);
PAINT ORANGE (-2140 2580);
FORCEPROP 2 LAST CDS_LIB mstr_discrete
J 0
(-2150 2500);
PAINT ORANGE (-2150 2500);
DISPLAY INVISIBLE (-2150 2500);
FORCEPROP 2 LAST ROOM VDDQ_GHJ_PWR_VR
J 0
(-2100 2650);
DISPLAY 1.361702 (-2100 2650);
PAINT ORANGE (-2100 2650);
DISPLAY INVISIBLE (-2100 2650);
FORCEPROP 1 LAST PATH I45
J 0
(-2100 2650);
DISPLAY 1.319149 (-2100 2650);
PAINT WHITE (-2100 2650);
DISPLAY INVISIBLE (-2100 2650);
FORCEPROP 2 LAST CDS_LOCATION C9U6
J 0
(-2100 2600);
DISPLAY 0.617021 (-2100 2600);
PAINT AQUA (-2100 2600);
DISPLAY INVISIBLE (-2100 2600);
FORCEPROP 2 LAST SEC 1
J 0
(-2100 2725);
DISPLAY 0.680851 (-2100 2725);
PAINT MONO (-2100 2725);
DISPLAY INVISIBLE (-2100 2725);
FORCEPROP 2 LAST SEC_TYPE 0805
J 0
(-2100 2725);
DISPLAY 1.021277 (-2100 2725);
PAINT ORANGE (-2100 2725);
DISPLAY INVISIBLE (-2100 2725);
FORCEADD CAP..1
(-1900 2500);
FORCEPROP 1 LASTPIN (-1900 2600) $PN 1
J 0
(-1890 2580);
DISPLAY 0.617021 (-1890 2580);
PAINT ORANGE (-1890 2580);
FORCEPROP 1 LAST MATERIAL X6S
J 0
(-1850 2400);
DISPLAY 0.617021 (-1850 2400);
PAINT SKYBLUE (-1850 2400);
FORCEPROP 1 LAST TOLERANCE 10%
J 0
(-1850 2450);
DISPLAY 0.617021 (-1850 2450);
PAINT SKYBLUE (-1850 2450);
FORCEPROP 1 LAST VOLTAGE 16V
J 0
(-1850 2500);
DISPLAY 0.617021 (-1850 2500);
PAINT SKYBLUE (-1850 2500);
FORCEPROP 1 LAST LOCATION C9U4
J 0
(-1850 2600);
DISPLAY 0.617021 (-1850 2600);
PAINT AQUA (-1850 2600);
FORCEPROP 1 LAST PACK_TYPE 0805
J 0
(-1850 2300);
DISPLAY 0.617021 (-1850 2300);
PAINT SKYBLUE (-1850 2300);
FORCEPROP 1 LAST PART_NUMBER C95333-007
J 0
(-1850 2350);
DISPLAY 0.617021 (-1850 2350);
PAINT BLUE (-1850 2350);
FORCEPROP 1 LASTPIN (-1900 2400) $PN 2
J 0
(-1890 2380);
DISPLAY 0.617021 (-1890 2380);
PAINT ORANGE (-1890 2380);
FORCEPROP 1 LAST VALUE 10UF
J 0
(-1850 2550);
DISPLAY 0.617021 (-1850 2550);
PAINT SKYBLUE (-1850 2550);
FORCEPROP 2 LAST SEC_TYPE 0805
J 0
(-1850 2725);
DISPLAY 1.021277 (-1850 2725);
PAINT ORANGE (-1850 2725);
DISPLAY INVISIBLE (-1850 2725);
FORCEPROP 2 LAST SEC 1
J 0
(-1850 2725);
DISPLAY 0.680851 (-1850 2725);
PAINT MONO (-1850 2725);
DISPLAY INVISIBLE (-1850 2725);
FORCEPROP 2 LAST CDS_LOCATION C9U4
J 0
(-1850 2600);
DISPLAY 0.617021 (-1850 2600);
PAINT AQUA (-1850 2600);
DISPLAY INVISIBLE (-1850 2600);
FORCEPROP 1 LAST PATH I46
J 0
(-1850 2650);
DISPLAY 1.319149 (-1850 2650);
PAINT WHITE (-1850 2650);
DISPLAY INVISIBLE (-1850 2650);
FORCEPROP 2 LAST ROOM VDDQ_GHJ_PWR_VR
J 0
(-1850 2650);
DISPLAY 1.361702 (-1850 2650);
PAINT ORANGE (-1850 2650);
DISPLAY INVISIBLE (-1850 2650);
FORCEPROP 2 LAST CDS_LIB mstr_discrete
J 0
(-1900 2500);
PAINT ORANGE (-1900 2500);
DISPLAY INVISIBLE (-1900 2500);
FORCEADD CAP..1
(-1650 2500);
FORCEPROP 1 LAST TOLERANCE 10%
J 0
(-1600 2450);
DISPLAY 0.617021 (-1600 2450);
PAINT SKYBLUE (-1600 2450);
FORCEPROP 1 LAST PACK_TYPE 0805
J 0
(-1600 2300);
DISPLAY 0.617021 (-1600 2300);
PAINT SKYBLUE (-1600 2300);
FORCEPROP 1 LAST LOCATION C9T4
J 0
(-1600 2600);
DISPLAY 0.617021 (-1600 2600);
PAINT AQUA (-1600 2600);
FORCEPROP 1 LAST PART_NUMBER C95333-007
J 0
(-1600 2350);
DISPLAY 0.617021 (-1600 2350);
PAINT BLUE (-1600 2350);
FORCEPROP 1 LAST VALUE 10UF
J 0
(-1600 2550);
DISPLAY 0.617021 (-1600 2550);
PAINT SKYBLUE (-1600 2550);
FORCEPROP 1 LAST VOLTAGE 16V
J 0
(-1600 2500);
DISPLAY 0.617021 (-1600 2500);
PAINT SKYBLUE (-1600 2500);
FORCEPROP 1 LAST MATERIAL X6S
J 0
(-1600 2400);
DISPLAY 0.617021 (-1600 2400);
PAINT SKYBLUE (-1600 2400);
FORCEPROP 1 LASTPIN (-1650 2600) $PN 1
J 0
(-1640 2580);
DISPLAY 0.617021 (-1640 2580);
PAINT ORANGE (-1640 2580);
FORCEPROP 1 LASTPIN (-1650 2400) $PN 2
J 0
(-1640 2380);
DISPLAY 0.617021 (-1640 2380);
PAINT ORANGE (-1640 2380);
FORCEPROP 2 LAST SEC_TYPE 0805
J 0
(-1600 2725);
DISPLAY 1.021277 (-1600 2725);
PAINT ORANGE (-1600 2725);
DISPLAY INVISIBLE (-1600 2725);
FORCEPROP 2 LAST ROOM VDDQ_GHJ_PWR_VR
J 0
(-1600 2650);
DISPLAY 1.361702 (-1600 2650);
PAINT ORANGE (-1600 2650);
DISPLAY INVISIBLE (-1600 2650);
FORCEPROP 1 LAST PATH I47
J 0
(-1600 2650);
DISPLAY 1.319149 (-1600 2650);
PAINT WHITE (-1600 2650);
DISPLAY INVISIBLE (-1600 2650);
FORCEPROP 2 LAST CDS_LOCATION C9T4
J 0
(-1600 2600);
DISPLAY 0.617021 (-1600 2600);
PAINT AQUA (-1600 2600);
DISPLAY INVISIBLE (-1600 2600);
FORCEPROP 2 LAST SEC 1
J 0
(-1600 2725);
DISPLAY 0.680851 (-1600 2725);
PAINT MONO (-1600 2725);
DISPLAY INVISIBLE (-1600 2725);
FORCEPROP 2 LAST CDS_LIB mstr_discrete
J 0
(-1650 2500);
PAINT ORANGE (-1650 2500);
DISPLAY INVISIBLE (-1650 2500);
FORCEADD CAP..1
(-1425 2500);
FORCEPROP 1 LAST VOLTAGE 16V
J 0
(-1375 2500);
DISPLAY 0.617021 (-1375 2500);
PAINT SKYBLUE (-1375 2500);
FORCEPROP 1 LASTPIN (-1425 2400) $PN 2
J 0
(-1415 2380);
DISPLAY 0.617021 (-1415 2380);
PAINT ORANGE (-1415 2380);
FORCEPROP 1 LASTPIN (-1425 2600) $PN 1
J 0
(-1415 2580);
DISPLAY 0.617021 (-1415 2580);
PAINT ORANGE (-1415 2580);
FORCEPROP 1 LAST MATERIAL X6S
J 0
(-1375 2400);
DISPLAY 0.617021 (-1375 2400);
PAINT SKYBLUE (-1375 2400);
FORCEPROP 1 LAST PACK_TYPE 0402
J 0
(-1375 2300);
DISPLAY 0.617021 (-1375 2300);
PAINT SKYBLUE (-1375 2300);
FORCEPROP 1 LAST TOLERANCE 10%
J 0
(-1375 2450);
DISPLAY 0.617021 (-1375 2450);
PAINT SKYBLUE (-1375 2450);
FORCEPROP 1 LAST VALUE 1.0UF
J 0
(-1375 2550);
DISPLAY 0.617021 (-1375 2550);
PAINT SKYBLUE (-1375 2550);
FORCEPROP 1 LAST PART_NUMBER D97712-011
J 0
(-1375 2350);
DISPLAY 0.617021 (-1375 2350);
PAINT BLUE (-1375 2350);
FORCEPROP 1 LAST LOCATION C1F27
J 0
(-1375 2600);
DISPLAY 0.617021 (-1375 2600);
PAINT AQUA (-1375 2600);
FORCEPROP 2 LAST CDS_LIB mstr_discrete
J 0
(-1425 2500);
PAINT ORANGE (-1425 2500);
DISPLAY INVISIBLE (-1425 2500);
FORCEPROP 2 LAST SEC_TYPE 0402
J 0
(-1375 2725);
DISPLAY 1.021277 (-1375 2725);
PAINT ORANGE (-1375 2725);
DISPLAY INVISIBLE (-1375 2725);
FORCEPROP 2 LAST SEC 1
J 0
(-1375 2725);
DISPLAY 0.680851 (-1375 2725);
PAINT MONO (-1375 2725);
DISPLAY INVISIBLE (-1375 2725);
FORCEPROP 1 LAST PATH I48
J 0
(-1375 2650);
DISPLAY 1.319149 (-1375 2650);
PAINT WHITE (-1375 2650);
DISPLAY INVISIBLE (-1375 2650);
FORCEPROP 2 LAST ROOM VDDQ_GHJ_PWR_VR
J 0
(-1375 2650);
DISPLAY 1.361702 (-1375 2650);
PAINT ORANGE (-1375 2650);
DISPLAY INVISIBLE (-1375 2650);
FORCEADD CAP..1
(-925 2500);
FORCEPROP 1 LAST MATERIAL X6S
J 0
(-875 2400);
DISPLAY 0.617021 (-875 2400);
PAINT SKYBLUE (-875 2400);
FORCEPROP 1 LAST VOLTAGE 16V
J 0
(-875 2500);
DISPLAY 0.617021 (-875 2500);
PAINT SKYBLUE (-875 2500);
FORCEPROP 1 LAST VALUE 1.0UF
J 0
(-875 2550);
DISPLAY 0.617021 (-875 2550);
PAINT SKYBLUE (-875 2550);
FORCEPROP 1 LAST LOCATION C1G6
J 0
(-875 2600);
DISPLAY 0.617021 (-875 2600);
PAINT AQUA (-875 2600);
FORCEPROP 1 LASTPIN (-925 2400) $PN 2
J 0
(-915 2380);
DISPLAY 0.617021 (-915 2380);
PAINT ORANGE (-915 2380);
FORCEPROP 1 LASTPIN (-925 2600) $PN 1
J 0
(-915 2580);
DISPLAY 0.617021 (-915 2580);
PAINT ORANGE (-915 2580);
FORCEPROP 1 LAST PACK_TYPE 0402
J 0
(-875 2300);
DISPLAY 0.617021 (-875 2300);
PAINT SKYBLUE (-875 2300);
FORCEPROP 1 LAST PART_NUMBER D97712-011
J 0
(-875 2350);
DISPLAY 0.617021 (-875 2350);
PAINT BLUE (-875 2350);
FORCEPROP 1 LAST TOLERANCE 10%
J 0
(-875 2450);
DISPLAY 0.617021 (-875 2450);
PAINT SKYBLUE (-875 2450);
FORCEPROP 2 LAST SEC_TYPE 0402
J 0
(-875 2725);
DISPLAY 1.021277 (-875 2725);
PAINT ORANGE (-875 2725);
DISPLAY INVISIBLE (-875 2725);
FORCEPROP 2 LAST ROOM VDDQ_GHJ_PWR_VR
J 0
(-875 2650);
DISPLAY 1.361702 (-875 2650);
PAINT ORANGE (-875 2650);
DISPLAY INVISIBLE (-875 2650);
FORCEPROP 1 LAST PATH I50
J 0
(-875 2650);
DISPLAY 1.319149 (-875 2650);
PAINT WHITE (-875 2650);
DISPLAY INVISIBLE (-875 2650);
FORCEPROP 2 LAST SEC 1
J 0
(-875 2725);
DISPLAY 0.680851 (-875 2725);
PAINT MONO (-875 2725);
DISPLAY INVISIBLE (-875 2725);
FORCEPROP 2 LAST CDS_LOCATION C1G6
J 0
(-875 2600);
DISPLAY 0.617021 (-875 2600);
PAINT AQUA (-875 2600);
DISPLAY INVISIBLE (-875 2600);
FORCEPROP 2 LAST CDS_LIB mstr_discrete
J 0
(-925 2500);
PAINT ORANGE (-925 2500);
DISPLAY INVISIBLE (-925 2500);
FORCEADD CAP_A..1
(-1175 2500);
FORCEPROP 1 LAST PACK_TYPE 0402V
J 0
(-1125 2300);
DISPLAY 0.617021 (-1125 2300);
PAINT SKYBLUE (-1125 2300);
FORCEPROP 1 LAST MATERIAL X7R
J 0
(-1125 2400);
DISPLAY 0.617021 (-1125 2400);
PAINT SKYBLUE (-1125 2400);
FORCEPROP 1 LASTPIN (-1175 2600) $PN 1
J 0
(-1165 2580);
DISPLAY 0.617021 (-1165 2580);
PAINT ORANGE (-1165 2580);
FORCEPROP 1 LASTPIN (-1175 2400) $PN 2
J 0
(-1165 2380);
DISPLAY 0.617021 (-1165 2380);
PAINT ORANGE (-1165 2380);
FORCEPROP 1 LAST LOCATION C1G14
J 0
(-1125 2600);
DISPLAY 0.617021 (-1125 2600);
PAINT AQUA (-1125 2600);
FORCEPROP 1 LAST VALUE 0.1UF
J 0
(-1125 2550);
DISPLAY 0.617021 (-1125 2550);
PAINT SKYBLUE (-1125 2550);
FORCEPROP 1 LAST VOLTAGE 16V
J 0
(-1125 2500);
DISPLAY 0.617021 (-1125 2500);
PAINT SKYBLUE (-1125 2500);
FORCEPROP 1 LAST TOLERANCE 10%
J 0
(-1125 2450);
DISPLAY 0.617021 (-1125 2450);
PAINT SKYBLUE (-1125 2450);
FORCEPROP 1 LAST PART_NUMBER A36096-030
J 0
(-1125 2350);
DISPLAY 0.617021 (-1125 2350);
PAINT BLUE (-1125 2350);
FORCEPROP 2 LAST SEC 1
J 0
(-1125 2725);
DISPLAY 0.680851 (-1125 2725);
PAINT MONO (-1125 2725);
DISPLAY INVISIBLE (-1125 2725);
FORCEPROP 2 LAST SEC_TYPE 0402V
J 0
(-1125 2725);
DISPLAY 1.021277 (-1125 2725);
PAINT ORANGE (-1125 2725);
DISPLAY INVISIBLE (-1125 2725);
FORCEPROP 2 LAST CDS_SEC 1
J 0
(-1125 2650);
PAINT ORANGE (-1125 2650);
DISPLAY INVISIBLE (-1125 2650);
FORCEPROP 2 LAST CDS_LOCATION C1G14
J 0
(-1125 2600);
DISPLAY 0.617021 (-1125 2600);
PAINT AQUA (-1125 2600);
DISPLAY INVISIBLE (-1125 2600);
FORCEPROP 2 LAST ROOM VDDQ_GHJ_PWR_VR
J 0
(-1125 2650);
DISPLAY 1.361702 (-1125 2650);
PAINT ORANGE (-1125 2650);
DISPLAY INVISIBLE (-1125 2650);
FORCEPROP 1 LAST PATH I51
J 0
(-1125 2650);
DISPLAY 0.978723 (-1125 2650);
PAINT WHITE (-1125 2650);
DISPLAY INVISIBLE (-1125 2650);
FORCEPROP 2 LAST CDS_LIB dev_discrete
J 0
(-1175 2500);
PAINT ORANGE (-1175 2500);
DISPLAY INVISIBLE (-1175 2500);
FORCEADD CAP..1
(25 2500);
FORCEPROP 1 LAST LOCATION C1G5
J 0
(75 2600);
DISPLAY 0.617021 (75 2600);
PAINT AQUA (75 2600);
FORCEPROP 1 LASTPIN (25 2600) $PN 1
J 0
(35 2580);
DISPLAY 0.617021 (35 2580);
PAINT ORANGE (35 2580);
FORCEPROP 1 LAST VALUE 0.22UF
J 0
(75 2550);
DISPLAY 0.617021 (75 2550);
PAINT SKYBLUE (75 2550);
FORCEPROP 1 LAST MATERIAL X7R
J 0
(250 2600);
DISPLAY 0.617021 (250 2600);
PAINT SKYBLUE (250 2600);
FORCEPROP 1 LASTPIN (25 2400) $PN 2
J 0
(35 2380);
DISPLAY 0.617021 (35 2380);
PAINT ORANGE (35 2380);
FORCEPROP 1 LAST TOLERANCE 10%
J 0
(75 2450);
DISPLAY 0.617021 (75 2450);
PAINT SKYBLUE (75 2450);
FORCEPROP 1 LAST VOLTAGE 16V
J 0
(75 2500);
DISPLAY 0.617021 (75 2500);
PAINT SKYBLUE (75 2500);
FORCEPROP 1 LAST PACK_TYPE 0402
J 0
(250 2500);
DISPLAY 0.617021 (250 2500);
PAINT SKYBLUE (250 2500);
FORCEPROP 1 LAST PART_NUMBER A36096-155
J 0
(250 2550);
DISPLAY 0.617021 (250 2550);
PAINT BLUE (250 2550);
FORCEPROP 2 LAST CDS_LIB mstr_discrete
J 0
(25 2500);
PAINT ORANGE (25 2500);
DISPLAY INVISIBLE (25 2500);
FORCEPROP 1 LAST PATH I54
J 0
(75 2650);
DISPLAY 1.319149 (75 2650);
PAINT WHITE (75 2650);
DISPLAY INVISIBLE (75 2650);
FORCEPROP 2 LAST ROOM VDDQ_GHJ_PWR_VR
J 0
(75 2650);
DISPLAY 1.361702 (75 2650);
PAINT ORANGE (75 2650);
DISPLAY INVISIBLE (75 2650);
FORCEPROP 2 LAST SEC_TYPE 0402
J 0
(75 2725);
DISPLAY 1.021277 (75 2725);
PAINT ORANGE (75 2725);
DISPLAY INVISIBLE (75 2725);
FORCEPROP 2 LAST SEC 1
J 0
(75 2725);
DISPLAY 0.680851 (75 2725);
PAINT MONO (75 2725);
DISPLAY INVISIBLE (75 2725);
FORCEPROP 2 LAST CDS_LOCATION C1G5
J 0
(75 2600);
DISPLAY 0.617021 (75 2600);
PAINT AQUA (75 2600);
DISPLAY INVISIBLE (75 2600);
FORCEADD OFFPAGE..2
(3450 2475);
FORCEPROP 2 LAST $XR1 223 
J 0
(3759 2475);
DISPLAY 0.638298 (3759 2475);
PAINT MONO (3759 2475);
FORCEPROP 2 LAST $XR0 224 
J 0
(3639 2475);
DISPLAY 0.638298 (3639 2475);
PAINT MONO (3639 2475);
FORCEPROP 2 LAST ROOM VDDQ_GHJ_PWR_VR
J 0
(3050 2550);
DISPLAY 1.936170 (3050 2550);
PAINT ORANGE (3050 2550);
DISPLAY INVISIBLE (3050 2550);
FORCEPROP 2 LAST CDS_LIB mstr_standard
J 0
(3450 2475);
PAINT ORANGE (3450 2475);
DISPLAY INVISIBLE (3450 2475);
FORCEPROP 2 LAST PATH I58
J 0
(3630 2550);
DISPLAY 1.361702 (3630 2550);
PAINT ORANGE (3630 2550);
DISPLAY INVISIBLE (3630 2550);
FORCEPROP 2 LAST BOM_COST VDDQ_GHJ_PWR_VR
J 0
(3650 2525);
DISPLAY 1.446809 (3650 2525);
PAINT MONO (3650 2525);
DISPLAY INVISIBLE (3650 2525);
FORCEPROP 1 LAST OFFPAGE TRUE
J 0
(3775 2350);
DISPLAY 1.723404 (3775 2350);
PAINT GREEN (3775 2350);
DISPLAY INVISIBLE (3775 2350);
FORCEPROP 1 LAST COMMENT_BODY TRUE
J 0
(3405 2380);
DISPLAY 1.723404 (3405 2380);
PAINT GREEN (3405 2380);
DISPLAY INVISIBLE (3405 2380);
FORCEADD CAP..1
(4500 1800);
FORCEPROP 1 LASTPIN (4500 1700) $PN 2
J 0
(4510 1680);
DISPLAY 0.617021 (4510 1680);
PAINT GREEN (4510 1680);
FORCEPROP 1 LAST MATERIAL X6S
J 0
(4550 1700);
DISPLAY 0.617021 (4550 1700);
PAINT SKYBLUE (4550 1700);
FORCEPROP 1 LASTPIN (4500 1900) $PN 1
J 0
(4510 1880);
DISPLAY 0.617021 (4510 1880);
PAINT GREEN (4510 1880);
FORCEPROP 1 LAST LOCATION C1G17
J 0
(4550 1900);
DISPLAY 0.617021 (4550 1900);
PAINT AQUA (4550 1900);
FORCEPROP 1 LAST VOLTAGE 4V
J 0
(4550 1800);
DISPLAY 0.723404 (4550 1800);
PAINT SKYBLUE (4550 1800);
FORCEPROP 1 LAST VALUE 22UF
J 0
(4550 1850);
DISPLAY 0.617021 (4550 1850);
PAINT SKYBLUE (4550 1850);
FORCEPROP 0 LAST GROUP PWR_MLCC_CAP
J 0
(4556 1562);
DISPLAY 0.638298 (4556 1562);
PAINT BROWN (4556 1562);
DISPLAY BOTH (4556 1562);
FORCEPROP 1 LAST PART_NUMBER C95333-002
J 0
(4550 1650);
DISPLAY 0.617021 (4550 1650);
PAINT BLUE (4550 1650);
FORCEPROP 1 LAST TOLERANCE 20%
J 0
(4550 1750);
DISPLAY 0.617021 (4550 1750);
PAINT SKYBLUE (4550 1750);
FORCEPROP 1 LAST PACK_TYPE 0805LF
J 0
(4550 1600);
DISPLAY 0.617021 (4550 1600);
PAINT SKYBLUE (4550 1600);
FORCEPROP 2 LAST SEC_TYPE 0805LF
J 0
(4555 2000);
DISPLAY 1.021277 (4555 2000);
PAINT ORANGE (4555 2000);
DISPLAY INVISIBLE (4555 2000);
FORCEPROP 2 LAST SEC 1
J 0
(4555 2000);
DISPLAY 0.680851 (4555 2000);
PAINT MONO (4555 2000);
DISPLAY INVISIBLE (4555 2000);
FORCEPROP 2 LAST BOM_COST VDDQ_GHJ_PWR_VR
J 0
(4550 1950);
DISPLAY 1.446809 (4550 1950);
PAINT MONO (4550 1950);
DISPLAY INVISIBLE (4550 1950);
FORCEPROP 1 LAST PATH I6
J 0
(4550 1950);
DISPLAY 0.978723 (4550 1950);
PAINT WHITE (4550 1950);
DISPLAY INVISIBLE (4550 1950);
FORCEPROP 2 LAST ROOM VDDQ_GHJ_PWR_VR
J 0
(4550 1950);
DISPLAY 1.446809 (4550 1950);
PAINT MONO (4550 1950);
DISPLAY INVISIBLE (4550 1950);
FORCEPROP 2 LAST CDS_LOCATION C1G17
J 0
(4550 1900);
DISPLAY 0.617021 (4550 1900);
PAINT AQUA (4550 1900);
DISPLAY INVISIBLE (4550 1900);
FORCEPROP 2 LAST CDS_LIB mstr_discrete
J 0
(4500 1800);
DISPLAY 1.936170 (4500 1800);
PAINT ORANGE (4500 1800);
DISPLAY INVISIBLE (4500 1800);
FORCEADD OFFPAGE..2
(3975 775);
FORCEPROP 2 LAST $XR0 223 
J 0
(4164 775);
DISPLAY 0.638298 (4164 775);
PAINT MONO (4164 775);
FORCEPROP 2 LAST CDS_LIB mstr_standard
J 0
(3975 775);
PAINT ORANGE (3975 775);
DISPLAY INVISIBLE (3975 775);
FORCEPROP 2 LAST BOM_COST VDDQ_GHJ_PWR_VR
J 0
(4175 825);
DISPLAY 1.446809 (4175 825);
PAINT MONO (4175 825);
DISPLAY INVISIBLE (4175 825);
FORCEPROP 2 LAST PATH I61
J 0
(4155 850);
DISPLAY 1.361702 (4155 850);
PAINT ORANGE (4155 850);
DISPLAY INVISIBLE (4155 850);
FORCEPROP 2 LAST ROOM VDDQ_GHJ_PWR_VR
J 0
(3575 850);
DISPLAY 1.936170 (3575 850);
PAINT ORANGE (3575 850);
DISPLAY INVISIBLE (3575 850);
FORCEPROP 1 LAST OFFPAGE TRUE
J 0
(4300 650);
DISPLAY 1.723404 (4300 650);
PAINT GREEN (4300 650);
DISPLAY INVISIBLE (4300 650);
FORCEPROP 1 LAST COMMENT_BODY TRUE
J 0
(3930 680);
DISPLAY 1.723404 (3930 680);
PAINT GREEN (3930 680);
DISPLAY INVISIBLE (3930 680);
FORCEADD OFFPAGE..2
(4000 425);
FORCEPROP 2 LAST $XR0 223 
J 0
(4189 425);
DISPLAY 0.638298 (4189 425);
PAINT MONO (4189 425);
FORCEPROP 2 LAST BOM_COST VDDQ_GHJ_PWR_VR
J 0
(4200 475);
DISPLAY 1.446809 (4200 475);
PAINT MONO (4200 475);
DISPLAY INVISIBLE (4200 475);
FORCEPROP 2 LAST PATH I62
J 0
(4180 500);
DISPLAY 1.361702 (4180 500);
PAINT ORANGE (4180 500);
DISPLAY INVISIBLE (4180 500);
FORCEPROP 2 LAST CDS_LIB mstr_standard
J 0
(4000 425);
PAINT ORANGE (4000 425);
DISPLAY INVISIBLE (4000 425);
FORCEPROP 2 LAST ROOM VDDQ_GHJ_PWR_VR
J 0
(3600 500);
DISPLAY 1.936170 (3600 500);
PAINT ORANGE (3600 500);
DISPLAY INVISIBLE (3600 500);
FORCEPROP 1 LAST OFFPAGE TRUE
J 0
(4325 300);
DISPLAY 1.723404 (4325 300);
PAINT GREEN (4325 300);
DISPLAY INVISIBLE (4325 300);
FORCEPROP 1 LAST COMMENT_BODY TRUE
J 0
(3955 330);
DISPLAY 1.723404 (3955 330);
PAINT GREEN (3955 330);
DISPLAY INVISIBLE (3955 330);
FORCEADD OFFPAGE..2
(3825 100);
FORCEPROP 2 LAST $XR1 223 
J 0
(4134 100);
DISPLAY 0.638298 (4134 100);
PAINT MONO (4134 100);
FORCEPROP 2 LAST $XR0 224 
J 0
(4014 100);
DISPLAY 0.638298 (4014 100);
PAINT MONO (4014 100);
FORCEPROP 2 LAST CDS_LIB mstr_standard
J 0
(3825 100);
PAINT ORANGE (3825 100);
DISPLAY INVISIBLE (3825 100);
FORCEPROP 2 LAST PATH I63
J 0
(4005 175);
DISPLAY 1.361702 (4005 175);
PAINT ORANGE (4005 175);
DISPLAY INVISIBLE (4005 175);
FORCEPROP 2 LAST BOM_COST VDDQ_GHJ_PWR_VR
J 0
(4025 150);
DISPLAY 1.446809 (4025 150);
PAINT MONO (4025 150);
DISPLAY INVISIBLE (4025 150);
FORCEPROP 2 LAST ROOM VDDQ_GHJ_PWR_VR
J 0
(3425 175);
DISPLAY 1.936170 (3425 175);
PAINT ORANGE (3425 175);
DISPLAY INVISIBLE (3425 175);
FORCEPROP 1 LAST OFFPAGE TRUE
J 0
(4150 -25);
DISPLAY 1.723404 (4150 -25);
PAINT GREEN (4150 -25);
DISPLAY INVISIBLE (4150 -25);
FORCEPROP 1 LAST COMMENT_BODY TRUE
J 0
(3780 5);
DISPLAY 1.723404 (3780 5);
PAINT GREEN (3780 5);
DISPLAY INVISIBLE (3780 5);
FORCEADD PVDDQ_GHJ..1
(4500 -325);
FORCEPROP 3 LASTPIN (4500 -375) SIG_NAME PVDDQ_GHJ\g
J 0
(4510 -365);
DISPLAY 0.659574 (4510 -365);
PAINT MONO (4510 -365);
DISPLAY INVISIBLE (4510 -365);
FORCEPROP 1 LAST VOLTAGE 1.2V
J 0
(4455 -368);
DISPLAY 0.340426 (4455 -368);
PAINT SKYBLUE (4455 -368);
DISPLAY INVISIBLE (4455 -368);
FORCEPROP 1 LAST PATH I64
J 0
(4550 -300);
DISPLAY 0.872340 (4550 -300);
PAINT AQUA (4550 -300);
DISPLAY INVISIBLE (4550 -300);
FORCEPROP 2 LAST CDS_LIB mstr_symbols
J 0
(4500 -325);
PAINT ORANGE (4500 -325);
DISPLAY INVISIBLE (4500 -325);
FORCEPROP 1 LAST BODY_TYPE PLUMBING
J 0
(4455 -368);
DISPLAY 0.340426 (4455 -368);
PAINT GREEN (4455 -368);
DISPLAY INVISIBLE (4455 -368);
FORCEPROP 1 LAST HDL_POWER PVDDQ_GHJ
J 1
(4500 -275);
DISPLAY 0.872340 (4500 -275);
PAINT GREEN (4500 -275);
DISPLAY INVISIBLE (4500 -275);
FORCEADD CAP..1
(4500 -575);
FORCEPROP 0 LAST BOM_SS NOPOP
J 0
(4550 -850);
DISPLAY 0.638298 (4550 -850);
PAINT BROWN (4550 -850);
DISPLAY BOTH (4550 -850);
FORCEPROP 1 LAST PACK_TYPE 0805LF
J 0
(4550 -775);
DISPLAY 0.617021 (4550 -775);
PAINT SKYBLUE (4550 -775);
FORCEPROP 1 LAST PART_NUMBER C95333-002
J 0
(4550 -725);
DISPLAY 0.617021 (4550 -725);
PAINT BLUE (4550 -725);
FORCEPROP 1 LAST VALUE 22UF
J 0
(4550 -525);
DISPLAY 0.617021 (4550 -525);
PAINT SKYBLUE (4550 -525);
FORCEPROP 1 LASTPIN (4500 -475) $PN 1
J 0
(4510 -495);
DISPLAY 0.617021 (4510 -495);
PAINT ORANGE (4510 -495);
FORCEPROP 1 LAST VOLTAGE 4V
J 0
(4550 -575);
DISPLAY 0.574468 (4550 -575);
PAINT SKYBLUE (4550 -575);
FORCEPROP 0 LAST GROUP PWR_MLCC_CAP
J 0
(4556 -813);
DISPLAY 0.638298 (4556 -813);
PAINT BROWN (4556 -813);
DISPLAY BOTH (4556 -813);
FORCEPROP 1 LAST MATERIAL X6S
J 0
(4550 -675);
DISPLAY 0.617021 (4550 -675);
PAINT SKYBLUE (4550 -675);
FORCEPROP 1 LASTPIN (4500 -675) $PN 2
J 0
(4510 -695);
DISPLAY 0.617021 (4510 -695);
PAINT ORANGE (4510 -695);
FORCEPROP 1 LAST TOLERANCE 20%
J 0
(4550 -625);
DISPLAY 0.617021 (4550 -625);
PAINT SKYBLUE (4550 -625);
FORCEPROP 1 LAST LOCATION C1G20
J 0
(4550 -475);
DISPLAY 0.617021 (4550 -475);
PAINT AQUA (4550 -475);
FORCEPROP 2 LAST SEC_TYPE 0805LF
J 0
(4555 -350);
DISPLAY 1.021277 (4555 -350);
PAINT ORANGE (4555 -350);
DISPLAY INVISIBLE (4555 -350);
FORCEPROP 2 LAST SEC 1
J 0
(4555 -350);
DISPLAY 0.680851 (4555 -350);
PAINT MONO (4555 -350);
DISPLAY INVISIBLE (4555 -350);
FORCEPROP 2 LAST BOM_COST VDDQ_GHJ_PWR_VR
J 0
(4550 -425);
DISPLAY 1.446809 (4550 -425);
PAINT MONO (4550 -425);
DISPLAY INVISIBLE (4550 -425);
FORCEPROP 1 LAST PATH I68
J 0
(4550 -425);
DISPLAY 1.319149 (4550 -425);
PAINT WHITE (4550 -425);
DISPLAY INVISIBLE (4550 -425);
FORCEPROP 2 LAST ROOM VDDQ_GHJ_PWR_VR
J 0
(4550 -425);
DISPLAY 1.446809 (4550 -425);
PAINT MONO (4550 -425);
DISPLAY INVISIBLE (4550 -425);
FORCEPROP 2 LAST CDS_LOCATION C1G20
J 0
(4550 -475);
DISPLAY 0.617021 (4550 -475);
PAINT AQUA (4550 -475);
DISPLAY INVISIBLE (4550 -475);
FORCEPROP 2 LAST CDS_LIB mstr_discrete
J 0
(4500 -575);
PAINT ORANGE (4500 -575);
DISPLAY INVISIBLE (4500 -575);
FORCEADD GND..1
(4500 -750);
FORCEPROP 3 LASTPIN (4500 -700) SIG_NAME GND\g
J 0
(4510 -690);
DISPLAY 0.659574 (4510 -690);
PAINT MONO (4510 -690);
DISPLAY INVISIBLE (4510 -690);
FORCEPROP 2 LAST CDS_LIB mstr_symbols
J 0
(4500 -750);
PAINT ORANGE (4500 -750);
DISPLAY INVISIBLE (4500 -750);
FORCEPROP 1 LAST VOLTAGE 0
J 0
(4500 -750);
PAINT SKYBLUE (4500 -750);
DISPLAY INVISIBLE (4500 -750);
FORCEPROP 1 LAST SIZE 1B
J 0
(4575 -800);
DISPLAY 1.723404 (4575 -800);
PAINT GREEN (4575 -800);
DISPLAY INVISIBLE (4575 -800);
FORCEPROP 1 LAST PATH I69
J 0
(4575 -750);
DISPLAY 1.170213 (4575 -750);
PAINT AQUA (4575 -750);
DISPLAY INVISIBLE (4575 -750);
FORCEPROP 2 LAST BOM_COST VDDQ_GHJ_PWR_VR
J 0
(4125 -675);
DISPLAY 1.446809 (4125 -675);
PAINT MONO (4125 -675);
DISPLAY INVISIBLE (4125 -675);
FORCEPROP 2 LAST ROOM VDDQ_GHJ_PWR_VR
J 0
(3950 -675);
DISPLAY 1.936170 (3950 -675);
PAINT ORANGE (3950 -675);
DISPLAY INVISIBLE (3950 -675);
FORCEPROP 1 LAST BODY_TYPE PLUMBING
J 0
(4455 -793);
DISPLAY 0.340426 (4455 -793);
PAINT GREEN (4455 -793);
DISPLAY INVISIBLE (4455 -793);
FORCEPROP 1 LAST HDL_POWER GND
J 0
(4500 -600);
DISPLAY 1.723404 (4500 -600);
PAINT GREEN (4500 -600);
DISPLAY INVISIBLE (4500 -600);
FORCEADD GND..1
(4500 1625);
FORCEPROP 3 LASTPIN (4500 1675) SIG_NAME GND\g
J 0
(4510 1685);
DISPLAY 0.659574 (4510 1685);
PAINT MONO (4510 1685);
DISPLAY INVISIBLE (4510 1685);
FORCEPROP 2 LAST BOM_COST VDDQ_GHJ_PWR_VR
J 0
(4125 1700);
DISPLAY 1.446809 (4125 1700);
PAINT MONO (4125 1700);
DISPLAY INVISIBLE (4125 1700);
FORCEPROP 1 LAST VOLTAGE 0
J 0
(4500 1625);
PAINT SKYBLUE (4500 1625);
DISPLAY INVISIBLE (4500 1625);
FORCEPROP 2 LAST CDS_LIB mstr_symbols
J 0
(4500 1625);
DISPLAY 1.936170 (4500 1625);
PAINT ORANGE (4500 1625);
DISPLAY INVISIBLE (4500 1625);
FORCEPROP 1 LAST SIZE 1B
J 0
(4575 1575);
DISPLAY 1.723404 (4575 1575);
PAINT GREEN (4575 1575);
DISPLAY INVISIBLE (4575 1575);
FORCEPROP 1 LAST PATH I7
J 0
(4575 1625);
DISPLAY 0.893617 (4575 1625);
PAINT AQUA (4575 1625);
DISPLAY INVISIBLE (4575 1625);
FORCEPROP 2 LAST ROOM VDDQ_GHJ_PWR_VR
J 0
(3950 1700);
DISPLAY 1.936170 (3950 1700);
PAINT ORANGE (3950 1700);
DISPLAY INVISIBLE (3950 1700);
FORCEPROP 1 LAST BODY_TYPE PLUMBING
J 0
(4455 1582);
DISPLAY 0.340426 (4455 1582);
PAINT GREEN (4455 1582);
DISPLAY INVISIBLE (4455 1582);
FORCEPROP 1 LAST HDL_POWER GND
J 0
(4500 1775);
DISPLAY 1.723404 (4500 1775);
PAINT GREEN (4500 1775);
DISPLAY INVISIBLE (4500 1775);
FORCEADD GND..1
(2500 -925);
FORCEPROP 3 LASTPIN (2500 -875) SIG_NAME GND\g
J 0
(2510 -865);
DISPLAY 0.659574 (2510 -865);
PAINT MONO (2510 -865);
DISPLAY INVISIBLE (2510 -865);
FORCEPROP 1 LAST PATH I70
J 0
(2575 -925);
DISPLAY 1.170213 (2575 -925);
PAINT AQUA (2575 -925);
DISPLAY INVISIBLE (2575 -925);
FORCEPROP 2 LAST CDS_LIB mstr_symbols
J 0
(2500 -925);
PAINT ORANGE (2500 -925);
DISPLAY INVISIBLE (2500 -925);
FORCEPROP 1 LAST SIZE 1B
J 0
(2575 -975);
DISPLAY 1.723404 (2575 -975);
PAINT GREEN (2575 -975);
DISPLAY INVISIBLE (2575 -975);
FORCEPROP 1 LAST VOLTAGE 0
J 0
(2500 -925);
PAINT SKYBLUE (2500 -925);
DISPLAY INVISIBLE (2500 -925);
FORCEPROP 2 LAST BOM_COST VDDQ_GHJ_PWR_VR
J 0
(2125 -850);
DISPLAY 1.446809 (2125 -850);
PAINT MONO (2125 -850);
DISPLAY INVISIBLE (2125 -850);
FORCEPROP 2 LAST ROOM VDDQ_GHJ_PWR_VR
J 0
(1950 -850);
DISPLAY 1.936170 (1950 -850);
PAINT ORANGE (1950 -850);
DISPLAY INVISIBLE (1950 -850);
FORCEPROP 1 LAST BODY_TYPE PLUMBING
J 0
(2455 -968);
DISPLAY 0.340426 (2455 -968);
PAINT GREEN (2455 -968);
DISPLAY INVISIBLE (2455 -968);
FORCEPROP 1 LAST HDL_POWER GND
J 0
(2500 -775);
DISPLAY 1.723404 (2500 -775);
PAINT GREEN (2500 -775);
DISPLAY INVISIBLE (2500 -775);
FORCEADD CAP..1
(100 150);
FORCEPROP 0 LAST BOM_SS NOPOP
J 0
(350 175);
DISPLAY 0.638298 (350 175);
PAINT BROWN (350 175);
DISPLAY BOTH (350 175);
FORCEPROP 1 LAST TOLERANCE 10%
J 0
(150 100);
DISPLAY 0.617021 (150 100);
PAINT SKYBLUE (150 100);
FORCEPROP 1 LASTPIN (100 50) $PN 2
J 0
(110 30);
DISPLAY 0.617021 (110 30);
PAINT ORANGE (110 30);
FORCEPROP 1 LASTPIN (100 250) $PN 1
J 0
(110 230);
DISPLAY 0.617021 (110 230);
PAINT ORANGE (110 230);
FORCEPROP 1 LAST PACK_TYPE 0402
J 0
(150 -50);
DISPLAY 0.617021 (150 -50);
PAINT SKYBLUE (150 -50);
FORCEPROP 1 LAST LOCATION C1G29
J 0
(150 250);
DISPLAY 0.617021 (150 250);
PAINT AQUA (150 250);
FORCEPROP 1 LAST PART_NUMBER A36096-155
J 0
(150 0);
DISPLAY 0.617021 (150 0);
PAINT BLUE (150 0);
FORCEPROP 1 LAST MATERIAL X7R
J 0
(150 50);
DISPLAY 0.617021 (150 50);
PAINT SKYBLUE (150 50);
FORCEPROP 1 LAST VOLTAGE 16V
J 0
(150 150);
DISPLAY 0.617021 (150 150);
PAINT SKYBLUE (150 150);
FORCEPROP 1 LAST VALUE 0.22UF
J 0
(150 200);
DISPLAY 0.617021 (150 200);
PAINT SKYBLUE (150 200);
FORCEPROP 2 LAST ROOM VDDQ_GHJ_PWR_VR
J 0
(150 300);
DISPLAY 1.361702 (150 300);
PAINT ORANGE (150 300);
DISPLAY INVISIBLE (150 300);
FORCEPROP 2 LAST SEC 1
J 0
(150 375);
DISPLAY 0.680851 (150 375);
PAINT MONO (150 375);
DISPLAY INVISIBLE (150 375);
FORCEPROP 2 LAST SEC_TYPE 0402
J 0
(150 375);
DISPLAY 1.021277 (150 375);
PAINT ORANGE (150 375);
DISPLAY INVISIBLE (150 375);
FORCEPROP 1 LAST PATH I72
J 0
(150 300);
DISPLAY 1.319149 (150 300);
PAINT WHITE (150 300);
DISPLAY INVISIBLE (150 300);
FORCEPROP 2 LAST CDS_LIB mstr_discrete
J 0
(100 150);
PAINT ORANGE (100 150);
DISPLAY INVISIBLE (100 150);
FORCEADD CAP..1
R 2
(-625 -475);
FORCEPROP 1 LAST MATERIAL X7R
J 2
(-675 -575);
DISPLAY 0.617021 (-675 -575);
PAINT SKYBLUE (-675 -575);
FORCEPROP 1 LAST PART_NUMBER A36096-104
J 2
(-675 -625);
DISPLAY 0.617021 (-675 -625);
PAINT BLUE (-675 -625);
FORCEPROP 1 LASTPIN (-625 -575) $PN 2
J 2
(-635 -595);
DISPLAY 0.617021 (-635 -595);
PAINT ORANGE (-635 -595);
FORCEPROP 1 LAST PACK_TYPE 0402
J 2
(-675 -675);
DISPLAY 0.617021 (-675 -675);
PAINT SKYBLUE (-675 -675);
FORCEPROP 1 LASTPIN (-625 -375) $PN 1
J 2
(-635 -395);
DISPLAY 0.617021 (-635 -395);
PAINT ORANGE (-635 -395);
FORCEPROP 0 LAST BOM_SS NOPOP
J 0
(-550 -550);
DISPLAY 0.638298 (-550 -550);
PAINT BROWN (-550 -550);
DISPLAY BOTH (-550 -550);
FORCEPROP 1 LAST TOLERANCE 10%
J 2
(-675 -525);
DISPLAY 0.617021 (-675 -525);
PAINT SKYBLUE (-675 -525);
FORCEPROP 1 LAST VOLTAGE 16V
J 2
(-675 -475);
DISPLAY 0.617021 (-675 -475);
PAINT SKYBLUE (-675 -475);
FORCEPROP 1 LAST LOCATION C1F26
J 2
(-675 -375);
DISPLAY 0.617021 (-675 -375);
PAINT AQUA (-675 -375);
FORCEPROP 1 LAST VALUE 0.220UF
J 2
(-675 -425);
DISPLAY 0.617021 (-675 -425);
PAINT SKYBLUE (-675 -425);
FORCEPROP 2 LAST CDS_LIB mstr_discrete
J 0
(-625 -475);
PAINT ORANGE (-625 -475);
DISPLAY INVISIBLE (-625 -475);
FORCEPROP 0 LAST SPOF TRUE
J 0
(-675 -275);
DISPLAY 1.021277 (-675 -275);
PAINT ORANGE (-675 -275);
DISPLAY INVISIBLE (-675 -275);
FORCEPROP 2 LAST SEC_TYPE 0402
J 0
(-675 -275);
DISPLAY 1.021277 (-675 -275);
PAINT ORANGE (-675 -275);
DISPLAY INVISIBLE (-675 -275);
FORCEPROP 2 LAST SEC 1
J 0
(-675 -275);
DISPLAY 0.680851 (-675 -275);
PAINT MONO (-675 -275);
DISPLAY INVISIBLE (-675 -275);
FORCEPROP 2 LAST CDS_LOCATION C1F26
J 2
(-675 -375);
DISPLAY 0.617021 (-675 -375);
PAINT AQUA (-675 -375);
DISPLAY INVISIBLE (-675 -375);
FORCEPROP 1 LAST PATH I75
J 2
(-675 -325);
DISPLAY 0.978723 (-675 -325);
PAINT WHITE (-675 -325);
DISPLAY INVISIBLE (-675 -325);
FORCEPROP 2 LAST ROOM VDDQ_GHJ_PWR_VR
J 0
(-675 -325);
DISPLAY 1.361702 (-675 -325);
PAINT ORANGE (-675 -325);
DISPLAY INVISIBLE (-675 -325);
FORCEADD CAP..1
(-800 125);
FORCEPROP 0 LAST BOM_SS NOPOP
J 0
(-750 -125);
DISPLAY 0.638298 (-750 -125);
PAINT BROWN (-750 -125);
DISPLAY BOTH (-750 -125);
FORCEPROP 1 LAST MATERIAL X6S
J 0
(-750 25);
DISPLAY 0.617021 (-750 25);
PAINT SKYBLUE (-750 25);
FORCEPROP 1 LASTPIN (-800 25) $PN 2
J 0
(-790 5);
DISPLAY 0.617021 (-790 5);
PAINT ORANGE (-790 5);
FORCEPROP 1 LAST VOLTAGE 16V
J 0
(-750 125);
DISPLAY 0.617021 (-750 125);
PAINT SKYBLUE (-750 125);
FORCEPROP 1 LAST PACK_TYPE 0402
J 0
(-750 -75);
DISPLAY 0.617021 (-750 -75);
PAINT SKYBLUE (-750 -75);
FORCEPROP 1 LAST TOLERANCE 10%
J 0
(-750 75);
DISPLAY 0.617021 (-750 75);
PAINT SKYBLUE (-750 75);
FORCEPROP 1 LAST VALUE 1.0UF
J 0
(-750 175);
DISPLAY 0.617021 (-750 175);
PAINT SKYBLUE (-750 175);
FORCEPROP 1 LASTPIN (-800 225) $PN 1
J 0
(-790 205);
DISPLAY 0.617021 (-790 205);
PAINT ORANGE (-790 205);
FORCEPROP 1 LAST LOCATION C1G28
J 0
(-750 225);
DISPLAY 0.617021 (-750 225);
PAINT AQUA (-750 225);
FORCEPROP 1 LAST PART_NUMBER D97712-011
J 0
(-750 -25);
DISPLAY 0.617021 (-750 -25);
PAINT BLUE (-750 -25);
FORCEPROP 2 LAST CDS_LIB mstr_discrete
J 0
(-800 125);
PAINT ORANGE (-800 125);
DISPLAY INVISIBLE (-800 125);
FORCEPROP 2 LAST ROOM VDDQ_GHJ_PWR_VR
J 0
(-750 275);
DISPLAY 1.361702 (-750 275);
PAINT ORANGE (-750 275);
DISPLAY INVISIBLE (-750 275);
FORCEPROP 1 LAST PATH I77
J 0
(-750 275);
DISPLAY 1.319149 (-750 275);
PAINT WHITE (-750 275);
DISPLAY INVISIBLE (-750 275);
FORCEPROP 2 LAST SEC 1
J 0
(-750 350);
DISPLAY 0.680851 (-750 350);
PAINT MONO (-750 350);
DISPLAY INVISIBLE (-750 350);
FORCEPROP 2 LAST SEC_TYPE 0402
J 0
(-750 350);
DISPLAY 1.021277 (-750 350);
PAINT ORANGE (-750 350);
DISPLAY INVISIBLE (-750 350);
FORCEADD CAP_A..1
(-1100 125);
FORCEPROP 1 LASTPIN (-1100 225) $PN 1
J 0
(-1090 205);
DISPLAY 0.617021 (-1090 205);
PAINT ORANGE (-1090 205);
FORCEPROP 1 LASTPIN (-1100 25) $PN 2
J 0
(-1090 5);
DISPLAY 0.617021 (-1090 5);
PAINT ORANGE (-1090 5);
FORCEPROP 1 LAST VOLTAGE 16V
J 0
(-1050 125);
DISPLAY 0.617021 (-1050 125);
PAINT SKYBLUE (-1050 125);
FORCEPROP 1 LAST VALUE 0.1UF
J 0
(-1050 175);
DISPLAY 0.617021 (-1050 175);
PAINT SKYBLUE (-1050 175);
FORCEPROP 1 LAST LOCATION C1F28
J 0
(-1050 225);
DISPLAY 0.617021 (-1050 225);
PAINT AQUA (-1050 225);
FORCEPROP 1 LAST MATERIAL X7R
J 0
(-1050 25);
DISPLAY 0.617021 (-1050 25);
PAINT SKYBLUE (-1050 25);
FORCEPROP 1 LAST TOLERANCE 10%
J 0
(-1050 75);
DISPLAY 0.617021 (-1050 75);
PAINT SKYBLUE (-1050 75);
FORCEPROP 1 LAST PACK_TYPE 0402V
J 0
(-1050 -75);
DISPLAY 0.617021 (-1050 -75);
PAINT SKYBLUE (-1050 -75);
FORCEPROP 1 LAST PART_NUMBER A36096-030
J 0
(-1050 -25);
DISPLAY 0.617021 (-1050 -25);
PAINT BLUE (-1050 -25);
FORCEPROP 2 LAST SEC 1
J 0
(-1050 350);
DISPLAY 0.680851 (-1050 350);
PAINT MONO (-1050 350);
DISPLAY INVISIBLE (-1050 350);
FORCEPROP 2 LAST SEC_TYPE 0402V
J 0
(-1050 350);
DISPLAY 1.021277 (-1050 350);
PAINT ORANGE (-1050 350);
DISPLAY INVISIBLE (-1050 350);
FORCEPROP 2 LAST CDS_SEC 1
J 0
(-1050 275);
PAINT ORANGE (-1050 275);
DISPLAY INVISIBLE (-1050 275);
FORCEPROP 2 LAST ROOM VDDQ_GHJ_PWR_VR
J 0
(-1050 275);
DISPLAY 1.361702 (-1050 275);
PAINT ORANGE (-1050 275);
DISPLAY INVISIBLE (-1050 275);
FORCEPROP 1 LAST PATH I78
J 0
(-1050 275);
DISPLAY 0.978723 (-1050 275);
PAINT WHITE (-1050 275);
DISPLAY INVISIBLE (-1050 275);
FORCEPROP 2 LAST CDS_LIB dev_discrete
J 0
(-1100 125);
PAINT ORANGE (-1100 125);
DISPLAY INVISIBLE (-1100 125);
FORCEADD CAP..1
(-1375 125);
FORCEPROP 1 LAST TOLERANCE 10%
J 0
(-1325 75);
DISPLAY 0.617021 (-1325 75);
PAINT SKYBLUE (-1325 75);
FORCEPROP 1 LAST MATERIAL X6S
J 0
(-1325 25);
DISPLAY 0.617021 (-1325 25);
PAINT SKYBLUE (-1325 25);
FORCEPROP 1 LASTPIN (-1375 25) $PN 2
J 0
(-1365 5);
DISPLAY 0.617021 (-1365 5);
PAINT ORANGE (-1365 5);
FORCEPROP 1 LAST PACK_TYPE 0402
J 0
(-1325 -75);
DISPLAY 0.617021 (-1325 -75);
PAINT SKYBLUE (-1325 -75);
FORCEPROP 1 LAST PART_NUMBER D97712-011
J 0
(-1325 -25);
DISPLAY 0.617021 (-1325 -25);
PAINT BLUE (-1325 -25);
FORCEPROP 1 LAST VOLTAGE 16V
J 0
(-1325 125);
DISPLAY 0.617021 (-1325 125);
PAINT SKYBLUE (-1325 125);
FORCEPROP 1 LAST VALUE 1.0UF
J 0
(-1325 175);
DISPLAY 0.617021 (-1325 175);
PAINT SKYBLUE (-1325 175);
FORCEPROP 1 LAST LOCATION C1G13
J 0
(-1325 225);
DISPLAY 0.617021 (-1325 225);
PAINT AQUA (-1325 225);
FORCEPROP 1 LASTPIN (-1375 225) $PN 1
J 0
(-1365 205);
DISPLAY 0.617021 (-1365 205);
PAINT ORANGE (-1365 205);
FORCEPROP 2 LAST CDS_LIB mstr_discrete
J 0
(-1375 125);
PAINT ORANGE (-1375 125);
DISPLAY INVISIBLE (-1375 125);
FORCEPROP 2 LAST CDS_LOCATION C1G13
J 0
(-1325 225);
DISPLAY 0.617021 (-1325 225);
PAINT AQUA (-1325 225);
DISPLAY INVISIBLE (-1325 225);
FORCEPROP 1 LAST PATH I79
J 0
(-1325 275);
DISPLAY 1.319149 (-1325 275);
PAINT WHITE (-1325 275);
DISPLAY INVISIBLE (-1325 275);
FORCEPROP 2 LAST ROOM VDDQ_GHJ_PWR_VR
J 0
(-1325 275);
DISPLAY 1.361702 (-1325 275);
PAINT ORANGE (-1325 275);
DISPLAY INVISIBLE (-1325 275);
FORCEPROP 2 LAST SEC_TYPE 0402
J 0
(-1325 350);
DISPLAY 1.021277 (-1325 350);
PAINT ORANGE (-1325 350);
DISPLAY INVISIBLE (-1325 350);
FORCEPROP 2 LAST SEC 1
J 0
(-1325 350);
DISPLAY 0.680851 (-1325 350);
PAINT MONO (-1325 350);
DISPLAY INVISIBLE (-1325 350);
FORCEADD CAP..1
(-1650 125);
FORCEPROP 1 LASTPIN (-1650 25) $PN 2
J 0
(-1640 5);
DISPLAY 0.617021 (-1640 5);
PAINT ORANGE (-1640 5);
FORCEPROP 1 LAST LOCATION C9U3
J 0
(-1600 225);
DISPLAY 0.617021 (-1600 225);
PAINT AQUA (-1600 225);
FORCEPROP 1 LASTPIN (-1650 225) $PN 1
J 0
(-1640 205);
DISPLAY 0.617021 (-1640 205);
PAINT ORANGE (-1640 205);
FORCEPROP 1 LAST MATERIAL X6S
J 0
(-1600 25);
DISPLAY 0.617021 (-1600 25);
PAINT SKYBLUE (-1600 25);
FORCEPROP 1 LAST TOLERANCE 10%
J 0
(-1600 75);
DISPLAY 0.617021 (-1600 75);
PAINT SKYBLUE (-1600 75);
FORCEPROP 1 LAST VOLTAGE 16V
J 0
(-1600 125);
DISPLAY 0.617021 (-1600 125);
PAINT SKYBLUE (-1600 125);
FORCEPROP 1 LAST VALUE 10UF
J 0
(-1600 175);
DISPLAY 0.617021 (-1600 175);
PAINT SKYBLUE (-1600 175);
FORCEPROP 1 LAST PACK_TYPE 0805
J 0
(-1600 -75);
DISPLAY 0.617021 (-1600 -75);
PAINT SKYBLUE (-1600 -75);
FORCEPROP 1 LAST PART_NUMBER C95333-007
J 0
(-1600 -25);
DISPLAY 0.617021 (-1600 -25);
PAINT BLUE (-1600 -25);
FORCEPROP 2 LAST CDS_LIB mstr_discrete
J 0
(-1650 125);
PAINT ORANGE (-1650 125);
DISPLAY INVISIBLE (-1650 125);
FORCEPROP 2 LAST CDS_LOCATION C9U3
J 0
(-1600 225);
DISPLAY 0.617021 (-1600 225);
PAINT AQUA (-1600 225);
DISPLAY INVISIBLE (-1600 225);
FORCEPROP 1 LAST PATH I80
J 0
(-1600 275);
DISPLAY 1.319149 (-1600 275);
PAINT WHITE (-1600 275);
DISPLAY INVISIBLE (-1600 275);
FORCEPROP 2 LAST ROOM VDDQ_GHJ_PWR_VR
J 0
(-1600 275);
DISPLAY 1.361702 (-1600 275);
PAINT ORANGE (-1600 275);
DISPLAY INVISIBLE (-1600 275);
FORCEPROP 2 LAST SEC_TYPE 0805
J 0
(-1600 350);
DISPLAY 1.021277 (-1600 350);
PAINT ORANGE (-1600 350);
DISPLAY INVISIBLE (-1600 350);
FORCEPROP 2 LAST SEC 1
J 0
(-1600 350);
DISPLAY 0.680851 (-1600 350);
PAINT MONO (-1600 350);
DISPLAY INVISIBLE (-1600 350);
FORCEADD CAP..1
(-1925 125);
FORCEPROP 1 LASTPIN (-1925 25) $PN 2
J 0
(-1915 5);
DISPLAY 0.617021 (-1915 5);
PAINT ORANGE (-1915 5);
FORCEPROP 1 LASTPIN (-1925 225) $PN 1
J 0
(-1915 205);
DISPLAY 0.617021 (-1915 205);
PAINT ORANGE (-1915 205);
FORCEPROP 1 LAST TOLERANCE 10%
J 0
(-1875 75);
DISPLAY 0.617021 (-1875 75);
PAINT SKYBLUE (-1875 75);
FORCEPROP 1 LAST MATERIAL X6S
J 0
(-1875 25);
DISPLAY 0.617021 (-1875 25);
PAINT SKYBLUE (-1875 25);
FORCEPROP 1 LAST PACK_TYPE 0805
J 0
(-1875 -75);
DISPLAY 0.617021 (-1875 -75);
PAINT SKYBLUE (-1875 -75);
FORCEPROP 1 LAST VOLTAGE 16V
J 0
(-1875 125);
DISPLAY 0.617021 (-1875 125);
PAINT SKYBLUE (-1875 125);
FORCEPROP 1 LAST VALUE 10UF
J 0
(-1875 175);
DISPLAY 0.617021 (-1875 175);
PAINT SKYBLUE (-1875 175);
FORCEPROP 1 LAST LOCATION C9T6
J 0
(-1875 225);
DISPLAY 0.617021 (-1875 225);
PAINT AQUA (-1875 225);
FORCEPROP 1 LAST PART_NUMBER C95333-007
J 0
(-1875 -25);
DISPLAY 0.617021 (-1875 -25);
PAINT BLUE (-1875 -25);
FORCEPROP 2 LAST ROOM VDDQ_GHJ_PWR_VR
J 0
(-1875 275);
DISPLAY 1.361702 (-1875 275);
PAINT ORANGE (-1875 275);
DISPLAY INVISIBLE (-1875 275);
FORCEPROP 1 LAST PATH I81
J 0
(-1875 275);
DISPLAY 1.319149 (-1875 275);
PAINT WHITE (-1875 275);
DISPLAY INVISIBLE (-1875 275);
FORCEPROP 2 LAST SEC 1
J 0
(-1875 350);
DISPLAY 0.680851 (-1875 350);
PAINT MONO (-1875 350);
DISPLAY INVISIBLE (-1875 350);
FORCEPROP 2 LAST SEC_TYPE 0805
J 0
(-1875 350);
DISPLAY 1.021277 (-1875 350);
PAINT ORANGE (-1875 350);
DISPLAY INVISIBLE (-1875 350);
FORCEPROP 2 LAST CDS_LOCATION C9T6
J 0
(-1875 225);
DISPLAY 0.617021 (-1875 225);
PAINT AQUA (-1875 225);
DISPLAY INVISIBLE (-1875 225);
FORCEPROP 2 LAST CDS_LIB mstr_discrete
J 0
(-1925 125);
PAINT ORANGE (-1925 125);
DISPLAY INVISIBLE (-1925 125);
FORCEADD OFFPAGE..1
(650 -225);
FORCEPROP 2 LAST $XR0 223 
J 0
(398 -225);
DISPLAY 0.638298 (398 -225);
PAINT MONO (398 -225);
FORCEPROP 1 LAST COMMENT_BODY TRUE
J 0
(775 -325);
DISPLAY 1.680851 (775 -325);
PAINT GREEN (775 -325);
DISPLAY INVISIBLE (775 -325);
FORCEPROP 1 LAST OFFPAGE TRUE
J 0
(975 -350);
DISPLAY 1.680851 (975 -350);
PAINT GREEN (975 -350);
DISPLAY INVISIBLE (975 -350);
FORCEPROP 2 LAST ROOM VDDQ_GHJ_PWR_VR
J 0
(250 -150);
DISPLAY 1.936170 (250 -150);
PAINT ORANGE (250 -150);
DISPLAY INVISIBLE (250 -150);
FORCEPROP 2 LAST BOM_COST VDDQ_GHJ_PWR_VR
J 0
(400 -175);
DISPLAY 1.446809 (400 -175);
PAINT MONO (400 -175);
DISPLAY INVISIBLE (400 -175);
FORCEPROP 2 LAST CDS_LIB mstr_standard
J 0
(650 -225);
PAINT ORANGE (650 -225);
DISPLAY INVISIBLE (650 -225);
FORCEPROP 2 LAST PATH I82
J 0
(705 -150);
DISPLAY 1.361702 (705 -150);
PAINT ORANGE (705 -150);
DISPLAY INVISIBLE (705 -150);
FORCEADD VCC_CORE..1
(-2200 400);
FORCEPROP 3 LASTPIN (-2200 350) SIG_NAME VR_FET_SW_P12V_STBY_PVDDQ_GHJ\g
J 0
(-2190 360);
DISPLAY 0.659574 (-2190 360);
PAINT MONO (-2190 360);
DISPLAY INVISIBLE (-2190 360);
FORCEPROP 1 LAST HDL_POWER VR_FET_SW_P12V_STBY_PVDDQ_GHJ
J 1
(-2025 450);
DISPLAY 0.617021 (-2025 450);
PAINT GREEN (-2025 450);
FORCEPROP 1 LAST PATH I83
J 0
(-2150 425);
DISPLAY 1.170213 (-2150 425);
PAINT AQUA (-2150 425);
DISPLAY INVISIBLE (-2150 425);
FORCEPROP 2 LAST CDS_LIB mstr_symbols
J 0
(-2200 400);
PAINT ORANGE (-2200 400);
DISPLAY INVISIBLE (-2200 400);
FORCEADD CAP..1
(-2200 125);
FORCEPROP 1 LAST VOLTAGE 16V
J 0
(-2150 125);
DISPLAY 0.617021 (-2150 125);
PAINT SKYBLUE (-2150 125);
FORCEPROP 1 LAST MATERIAL X6S
J 0
(-2150 25);
DISPLAY 0.617021 (-2150 25);
PAINT SKYBLUE (-2150 25);
FORCEPROP 1 LAST VALUE 10UF
J 0
(-2150 175);
DISPLAY 0.617021 (-2150 175);
PAINT SKYBLUE (-2150 175);
FORCEPROP 1 LAST TOLERANCE 10%
J 0
(-2150 75);
DISPLAY 0.617021 (-2150 75);
PAINT SKYBLUE (-2150 75);
FORCEPROP 1 LASTPIN (-2200 225) $PN 1
J 0
(-2190 205);
DISPLAY 0.617021 (-2190 205);
PAINT ORANGE (-2190 205);
FORCEPROP 1 LAST LOCATION C9T9
J 0
(-2150 225);
DISPLAY 0.617021 (-2150 225);
PAINT AQUA (-2150 225);
FORCEPROP 1 LASTPIN (-2200 25) $PN 2
J 0
(-2190 5);
DISPLAY 0.617021 (-2190 5);
PAINT ORANGE (-2190 5);
FORCEPROP 1 LAST PART_NUMBER C95333-007
J 0
(-2150 -25);
DISPLAY 0.617021 (-2150 -25);
PAINT BLUE (-2150 -25);
FORCEPROP 1 LAST PACK_TYPE 0805
J 0
(-2150 -75);
DISPLAY 0.617021 (-2150 -75);
PAINT SKYBLUE (-2150 -75);
FORCEPROP 2 LAST SEC 1
J 0
(-2150 350);
DISPLAY 0.680851 (-2150 350);
PAINT MONO (-2150 350);
DISPLAY INVISIBLE (-2150 350);
FORCEPROP 2 LAST SEC_TYPE 0805
J 0
(-2150 350);
DISPLAY 1.021277 (-2150 350);
PAINT ORANGE (-2150 350);
DISPLAY INVISIBLE (-2150 350);
FORCEPROP 1 LAST PATH I84
J 0
(-2150 275);
DISPLAY 1.319149 (-2150 275);
PAINT WHITE (-2150 275);
DISPLAY INVISIBLE (-2150 275);
FORCEPROP 2 LAST ROOM VDDQ_GHJ_PWR_VR
J 0
(-2150 275);
DISPLAY 1.361702 (-2150 275);
PAINT ORANGE (-2150 275);
DISPLAY INVISIBLE (-2150 275);
FORCEPROP 2 LAST CDS_LIB mstr_discrete
J 0
(-2200 125);
PAINT ORANGE (-2200 125);
DISPLAY INVISIBLE (-2200 125);
FORCEADD GND..1
(-2200 -225);
FORCEPROP 3 LASTPIN (-2200 -175) SIG_NAME GND\g
J 0
(-2190 -165);
DISPLAY 0.659574 (-2190 -165);
PAINT MONO (-2190 -165);
DISPLAY INVISIBLE (-2190 -165);
FORCEPROP 1 LAST HDL_POWER GND
J 0
(-2200 -75);
DISPLAY 1.723404 (-2200 -75);
PAINT GREEN (-2200 -75);
DISPLAY INVISIBLE (-2200 -75);
FORCEPROP 1 LAST BODY_TYPE PLUMBING
J 0
(-2245 -268);
DISPLAY 0.340426 (-2245 -268);
PAINT GREEN (-2245 -268);
DISPLAY INVISIBLE (-2245 -268);
FORCEPROP 1 LAST PATH I85
J 0
(-2125 -225);
DISPLAY 1.170213 (-2125 -225);
PAINT AQUA (-2125 -225);
DISPLAY INVISIBLE (-2125 -225);
FORCEPROP 2 LAST CDS_LIB mstr_symbols
J 0
(-2200 -225);
PAINT ORANGE (-2200 -225);
DISPLAY INVISIBLE (-2200 -225);
FORCEPROP 1 LAST VOLTAGE 0
J 0
(-2200 -225);
PAINT SKYBLUE (-2200 -225);
DISPLAY INVISIBLE (-2200 -225);
FORCEPROP 1 LAST SIZE 1B
J 0
(-2125 -275);
DISPLAY 1.723404 (-2125 -275);
PAINT GREEN (-2125 -275);
DISPLAY INVISIBLE (-2125 -275);
FORCEPROP 2 LAST BOM_COST VDDQ_GHJ_PWR_VR
J 0
(-2575 -150);
DISPLAY 1.446809 (-2575 -150);
PAINT MONO (-2575 -150);
DISPLAY INVISIBLE (-2575 -150);
FORCEPROP 2 LAST ROOM VDDQ_GHJ_PWR_VR
J 0
(-2750 -150);
DISPLAY 1.936170 (-2750 -150);
PAINT ORANGE (-2750 -150);
DISPLAY INVISIBLE (-2750 -150);
FORCEADD P5V_STBY..1
(350 3150);
FORCEPROP 3 LASTPIN (350 3100) SIG_NAME P5V_STBY\g
J 0
(360 3110);
DISPLAY 0.659574 (360 3110);
PAINT MONO (360 3110);
DISPLAY INVISIBLE (360 3110);
FORCEPROP 1 LAST SIZE 1B
J 0
(395 3172);
DISPLAY 0.340426 (395 3172);
PAINT GREEN (395 3172);
DISPLAY INVISIBLE (395 3172);
FORCEPROP 1 LAST PATH I87
J 0
(395 3152);
DISPLAY 0.340426 (395 3152);
PAINT GREEN (395 3152);
DISPLAY INVISIBLE (395 3152);
FORCEPROP 2 LAST CDS_LIB mstr_symbols
J 0
(350 3150);
PAINT ORANGE (350 3150);
DISPLAY INVISIBLE (350 3150);
FORCEPROP 1 LAST VOLTAGE 5.0V
J 0
(305 3107);
DISPLAY 0.340426 (305 3107);
PAINT SKYBLUE (305 3107);
DISPLAY INVISIBLE (305 3107);
FORCEPROP 1 LAST BODY_TYPE PLUMBING
J 0
(305 3107);
DISPLAY 0.340426 (305 3107);
PAINT GREEN (305 3107);
DISPLAY INVISIBLE (305 3107);
FORCEPROP 1 LAST HDL_POWER P5V_STBY
J 0
(50 3025);
DISPLAY 0.872340 (50 3025);
PAINT ORANGE (50 3025);
DISPLAY INVISIBLE (50 3025);
FORCEADD P5V_STBY..1
(550 800);
FORCEPROP 3 LASTPIN (550 750) SIG_NAME P5V_STBY\g
J 0
(560 760);
DISPLAY 0.659574 (560 760);
PAINT MONO (560 760);
DISPLAY INVISIBLE (560 760);
FORCEPROP 1 LAST PATH I88
J 0
(595 802);
DISPLAY 0.340426 (595 802);
PAINT GREEN (595 802);
DISPLAY INVISIBLE (595 802);
FORCEPROP 2 LAST CDS_LIB mstr_symbols
J 0
(550 800);
PAINT ORANGE (550 800);
DISPLAY INVISIBLE (550 800);
FORCEPROP 1 LAST SIZE 1B
J 0
(595 822);
DISPLAY 0.340426 (595 822);
PAINT GREEN (595 822);
DISPLAY INVISIBLE (595 822);
FORCEPROP 1 LAST VOLTAGE 5.0V
J 0
(505 757);
DISPLAY 0.340426 (505 757);
PAINT SKYBLUE (505 757);
DISPLAY INVISIBLE (505 757);
FORCEPROP 1 LAST BODY_TYPE PLUMBING
J 0
(505 757);
DISPLAY 0.340426 (505 757);
PAINT GREEN (505 757);
DISPLAY INVISIBLE (505 757);
FORCEPROP 1 LAST HDL_POWER P5V_STBY
J 0
(250 675);
DISPLAY 0.872340 (250 675);
PAINT ORANGE (250 675);
DISPLAY INVISIBLE (250 675);
FORCEADD VCC_CORE..1
(-1700 2900);
FORCEPROP 3 LASTPIN (-1700 2850) SIG_NAME VR_FET_SW_P12V_STBY_PVDDQ_GHJ\g
J 0
(-1690 2860);
DISPLAY 0.659574 (-1690 2860);
PAINT MONO (-1690 2860);
DISPLAY INVISIBLE (-1690 2860);
FORCEPROP 1 LAST HDL_POWER VR_FET_SW_P12V_STBY_PVDDQ_GHJ
J 1
(-1625 2950);
DISPLAY 0.617021 (-1625 2950);
PAINT GREEN (-1625 2950);
FORCEPROP 2 LAST CDS_LIB mstr_symbols
J 0
(-1700 2900);
PAINT ORANGE (-1700 2900);
DISPLAY INVISIBLE (-1700 2900);
FORCEPROP 1 LAST PATH I89
J 0
(-1650 2925);
DISPLAY 0.872340 (-1650 2925);
PAINT AQUA (-1650 2925);
DISPLAY INVISIBLE (-1650 2925);
FORCEADD DNS..2
(4655 20);
PAINT RED (4655 20);
FORCEPROP 2 LAST CDS_LIB mstr_misc
J 0
(4655 20);
PAINT ORANGE (4655 20);
DISPLAY INVISIBLE (4655 20);
FORCEPROP 1 LAST COMMENT_BODY TRUE
R 1
J 0
(4730 -205);
DISPLAY 0.872340 (4730 -205);
PAINT GREEN (4730 -205);
DISPLAY INVISIBLE (4730 -205);
FORCEADD INTEL_CORP_BPAGE..1
(5450 -1675);
FORCEPROP 1 LAST CDS_CON_LAST_MODIFIED Fri Jun 16 17:49:21 2017
J 0
(4025 -1350);
DISPLAY 1.936170 (4025 -1350);
PAINT GREEN (4025 -1350);
DISPLAY INVISIBLE (4025 -1350);
FORCEPROP 2 LAST CUSTOM_TXT_CDS <XR_PAGE_TITLE>
J 0
(-2440 3575);
DISPLAY 0.638298 (-2440 3575);
PAINT PINK (-2440 3575);
DISPLAY INVISIBLE (-2440 3575);
FORCEPROP 2 LAST CUSTOM_TXT_CDS <CURRENT_DESIGN_SHEET> OF <TOTAL_DESIGN_SHEETS>
J 0
(4950 -1650);
PAINT ORANGE (4950 -1650);
FORCEPROP 2 LAST CUSTOM_TXT_CDS <CON_LAST_MODIFIED>
J 0
(1450 -1575);
PAINT ORANGE (1450 -1575);
FORCEPROP 1 LAST SCH_TITLE VDDQ GHJ VR(2 OF 3)
J 0
(-2500 -1625);
DISPLAY 1.212766 (-2500 -1625);
PAINT ORANGE (-2500 -1625);
FORCEPROP 2 LAST CDS_LIB mstr_symbols
J 0
(5450 -1675);
DISPLAY 1.936170 (5450 -1675);
PAINT ORANGE (5450 -1675);
DISPLAY INVISIBLE (5450 -1675);
FORCEPROP 2 LAST PAGE_BORDER TRUE
J 0
(-2440 3575);
DISPLAY 1.255319 (-2440 3575);
PAINT PINK (-2440 3575);
DISPLAY INVISIBLE (-2440 3575);
FORCEPROP 2 LAST ROOM VDDQ_GHJ_PWR_VR
J 0
(-2650 3425);
DISPLAY 1.936170 (-2650 3425);
PAINT ORANGE (-2650 3425);
DISPLAY INVISIBLE (-2650 3425);
FORCEPROP 1 LAST COMMENT_BODY TRUE
J 0
(5462 -1663);
DISPLAY 0.893617 (5462 -1663);
PAINT GREEN (5462 -1663);
DISPLAY INVISIBLE (5462 -1663);
FORCEPROP 2 LAST CDS_XR_PAGE_TITLE CR-224 : @BASEBOARD_FAB2_LIB.BASEBOARD_FAB2(SCH_1):PAGE224
J 0
(-2440 3575);
DISPLAY 0.638298 (-2440 3575);
PAINT PINK (-2440 3575);
DISPLAY INVISIBLE (-2440 3575);
FORCEADD DNS..2
(4630 2395);
PAINT RED (4630 2395);
FORCEPROP 2 LAST CDS_LIB mstr_misc
J 0
(4630 2395);
PAINT ORANGE (4630 2395);
DISPLAY INVISIBLE (4630 2395);
FORCEPROP 1 LAST COMMENT_BODY TRUE
R 1
J 0
(4705 2170);
DISPLAY 0.872340 (4705 2170);
PAINT GREEN (4705 2170);
DISPLAY INVISIBLE (4705 2170);
WIRE 16 -1 (4500 1950)(4500 2000);
WIRE 16 -1 (4500 1950)(4400 1950);
WIRE 16 -1 (4500 1900)(4500 1950);
WIRE 16 -1 (4400 1200)(4400 1950);
WIRE 16 -1 (4100 1950)(4400 1950);
WIRE 16 -1 (1200 1200)(4400 1200);
WIRE 16 -1 (1200 2400)(1200 1200);
WIRE 16 -1 (1325 2400)(1200 2400);
WIRE 16 -1 (4625 2275)(4625 2300);
WIRE 16 -1 (4650 -100)(4650 -75);
WIRE 16 -1 (1050 1625)(1050 1525);
WIRE 16 -1 (2900 1350)(2900 1300);
WIRE 16 -1 (2950 2125)(2950 2075);
WIRE 16 -1 (1150 -725)(1150 -825);
WIRE 16 -1 (3050 -175)(3050 -250);
WIRE 16 -1 (2675 1550)(2675 1700);
WIRE 16 -1 (2675 1700)(2675 1750);
WIRE 16 -1 (2675 1700)(2325 1700);
WIRE 16 -1 (2675 1750)(2675 1800);
WIRE 16 -1 (2675 1750)(2325 1750);
WIRE 16 -1 (2675 1800)(2675 1850);
WIRE 16 -1 (2675 1800)(2325 1800);
WIRE 16 -1 (2325 1850)(2675 1850);
WIRE 16 -1 (-1950 2075)(-1950 2200);
WIRE 16 -1 (-1950 2200)(-1900 2200);
WIRE 16 -1 (-1950 2200)(-2150 2200);
WIRE 16 -1 (-2150 2400)(-2150 2200);
WIRE 16 -1 (-1900 2200)(-1650 2200);
WIRE 16 -1 (-1900 2400)(-1900 2200);
WIRE 16 -1 (-1650 2200)(-1425 2200);
WIRE 16 -1 (-1650 2400)(-1650 2200);
WIRE 16 -1 (-1425 2200)(-1175 2200);
WIRE 16 -1 (-1425 2400)(-1425 2200);
WIRE 16 -1 (-1175 2200)(-925 2200);
WIRE 16 -1 (-1175 2400)(-1175 2200);
WIRE 16 -1 (-375 2200)(-925 2200);
WIRE 16 -1 (-925 2400)(-925 2200);
WIRE 16 -1 (25 2200)(-375 2200);
WIRE 16 -1 (-375 2425)(-375 2200);
WIRE 16 -1 (25 2400)(25 2200);
WIRE 16 -1 (4500 -425)(4500 -375);
WIRE 16 -1 (4400 -425)(4500 -425);
WIRE 16 -1 (4500 -475)(4500 -425);
WIRE 16 -1 (4400 -1150)(4400 -425);
WIRE 16 -1 (4050 -425)(4400 -425);
WIRE 16 -1 (1225 -1150)(4400 -1150);
WIRE 16 -1 (1225 25)(1225 -1150);
WIRE 16 -1 (1350 25)(1225 25);
WIRE 16 -1 (4500 -700)(4500 -675);
WIRE 16 -1 (4500 1675)(4500 1700);
WIRE 16 -1 (2500 -875)(2500 -675);
WIRE 16 -1 (2500 -675)(2500 -625);
WIRE 16 -1 (2500 -675)(2350 -675);
WIRE 16 -1 (2500 -625)(2500 -575);
WIRE 16 -1 (2500 -625)(2350 -625);
WIRE 16 -1 (2500 -575)(2500 -525);
WIRE 16 -1 (2500 -575)(2350 -575);
WIRE 16 -1 (2350 -525)(2500 -525);
WIRE 16 -1 (-2200 350)(-2200 325);
WIRE 16 -1 (-2200 325)(-1925 325);
WIRE 16 -1 (-2200 225)(-2200 325);
WIRE 16 -1 (-1650 325)(-1925 325);
WIRE 16 -1 (-1925 225)(-1925 325);
WIRE 16 -1 (-1375 325)(-1650 325);
WIRE 16 -1 (-1650 225)(-1650 325);
WIRE 16 -1 (-1375 325)(-1100 325);
WIRE 16 -1 (-1375 225)(-1375 325);
WIRE 16 -1 (1075 325)(-1100 325);
WIRE 16 -1 (-1100 225)(-1100 325);
WIRE 16 -1 (1075 375)(1075 325);
WIRE 16 -1 (1350 325)(1075 325);
WIRE 16 -1 (1350 375)(1075 375);
WIRE 16 -1 (-2200 -175)(-2200 -150);
WIRE 16 -1 (-2200 -150)(-1925 -150);
WIRE 16 -1 (-2200 25)(-2200 -150);
WIRE 16 -1 (-1925 -150)(-1650 -150);
WIRE 16 -1 (-1925 25)(-1925 -150);
WIRE 16 -1 (-1375 -150)(-1650 -150);
WIRE 16 -1 (-1650 25)(-1650 -150);
WIRE 16 -1 (-1375 -150)(-1100 -150);
WIRE 16 -1 (-1375 25)(-1375 -150);
WIRE 16 -1 (-1100 -150)(-800 -150);
WIRE 16 -1 (-1100 25)(-1100 -150);
WIRE 16 -1 (-800 -150)(-250 -150);
WIRE 16 -1 (-800 25)(-800 -150);
WIRE 16 -1 (100 -150)(-250 -150);
WIRE 16 -1 (-250 75)(-250 -150);
WIRE 16 -1 (100 50)(100 -150);
WIRE 16 -1 (350 3050)(350 3100);
WIRE 16 -1 (350 2600)(350 3050);
WIRE 16 -1 (25 3050)(350 3050);
WIRE 16 -1 (25 3050)(-375 3050);
WIRE 16 -1 (25 2600)(25 3050);
WIRE 16 -1 (1175 2600)(350 2600);
WIRE 16 -1 (1175 2500)(1175 2600);
WIRE 16 -1 (1325 2600)(1175 2600);
WIRE 16 -1 (-600 3050)(-375 3050);
WIRE 16 -1 (-375 2575)(-375 3050);
WIRE 16 -1 (1325 2500)(1175 2500);
WIRE 16 -1 (550 675)(550 750);
WIRE 16 -1 (550 675)(550 225);
WIRE 16 -1 (550 675)(100 675);
WIRE 16 -1 (100 675)(-250 675);
WIRE 16 -1 (100 250)(100 675);
WIRE 16 -1 (550 225)(1275 225);
WIRE 16 -1 (1275 125)(1275 225);
WIRE 16 -1 (1275 225)(1350 225);
WIRE 16 -1 (-450 675)(-250 675);
WIRE 16 -1 (-250 225)(-250 675);
WIRE 16 -1 (1350 125)(1275 125);
WIRE 16 -1 (-1700 2850)(-1700 2700);
WIRE 16 -1 (-1700 2700)(-1650 2700);
WIRE 16 -1 (-1900 2700)(-1700 2700);
WIRE 16 -1 (-2150 2700)(-1900 2700);
WIRE 16 -1 (-1900 2600)(-1900 2700);
WIRE 16 -1 (-1650 2700)(-1425 2700);
WIRE 16 -1 (-1650 2600)(-1650 2700);
WIRE 16 -1 (-1425 2700)(-1175 2700);
WIRE 16 -1 (-1425 2600)(-1425 2700);
WIRE 16 -1 (-2150 2600)(-2150 2700);
WIRE 16 -1 (1075 2700)(-1175 2700);
WIRE 16 -1 (-1175 2600)(-1175 2700);
WIRE 16 -1 (1075 2750)(1075 2700);
WIRE 16 -1 (1325 2700)(1075 2700);
WIRE 16 -1 (1325 2750)(1075 2750);
WIRE 16 -1 (350 2250)(1325 2250);
FORCEPROP 0 LAST SIG_NAME TP_PVDDQ_GHJ_PH1_GL_0
J 0
(377 2265);
DISPLAY 0.617021 (377 2265);
PAINT ORANGE (377 2265);
FORCEPROP 2 LASTPROP $XRERR UNIQUE?
J 0
(110 2250);
DISPLAY 0.638298 (110 2250);
PAINT MONO (110 2250);
DISPLAY INVISIBLE (110 2250);
WIRE 3 682 (-2350 550)(-2350 -250);
WIRE 3 682 (-850 550)(-2350 550);
WIRE 3 682 (-2350 -250)(-850 -250);
WIRE 3 682 (-850 -250)(-850 550);
WIRE 16 2175 (-425 -75)(325 -75);
WIRE 16 2175 (325 300)(325 -75);
WIRE 16 2175 (-425 300)(-425 -75);
WIRE 16 2175 (-425 300)(325 300);
WIRE 16 2175 (-950 -675)(100 -675);
WIRE 16 2175 (100 -275)(100 -675);
WIRE 16 2175 (-950 -275)(-950 -675);
WIRE 16 2175 (-950 -275)(100 -275);
WIRE 16 -1 (-800 675)(-650 675);
WIRE 16 -1 (-800 225)(-800 425);
WIRE 16 -1 (-800 675)(-800 425);
WIRE 16 -1 (-800 425)(1350 425);
FORCEPROP 2 LAST SIG_NAME VR_PVDDQ_GHJ_PH2_VCIN
J 0
(-765 435);
DISPLAY 0.617021 (-765 435);
PAINT ORANGE (-765 435);
FORCEPROP 2 LASTPROP $XRERR UNIQUE?
J 0
(-1005 435);
DISPLAY 0.638298 (-1005 435);
PAINT MONO (-1005 435);
DISPLAY INVISIBLE (-1005 435);
WIRE 3 682 (-2425 900)(-2425 -1300);
WIRE 3 682 (5200 900)(-2425 900);
WIRE 3 682 (-2425 -1300)(5200 -1300);
WIRE 3 682 (5200 -1300)(5200 900);
WIRE 3 2175 (-725 775)(-725 525);
WIRE 3 2175 (-725 525)(-375 525);
WIRE 3 2175 (-725 775)(-375 775);
WIRE 3 2175 (-375 775)(-375 525);
WIRE 3 2175 (150 -525)(450 -525);
WIRE 3 2175 (450 -250)(450 -525);
WIRE 3 2175 (150 -250)(150 -525);
WIRE 3 2175 (150 -250)(450 -250);
WIRE 16 -1 (700 -225)(1350 -225);
FORCEPROP 2 LAST SIG_NAME VR_PVDDQ_GHJ_PWM2
J 0
(687 -215);
DISPLAY 0.617021 (687 -215);
PAINT ORANGE (687 -215);
WIRE 16 -1 (2950 2325)(2950 2475);
WIRE 16 -1 (2950 2475)(3400 2475);
WIRE 16 -1 (2325 2475)(2325 2300);
WIRE 16 -1 (2325 2475)(2950 2475);
FORCEPROP 2 LAST SIG_NAME A_TSENSE_PVDDQ_GHJ
J 0
(2562 2485);
DISPLAY 0.617021 (2562 2485);
PAINT ORANGE (2562 2485);
WIRE 3 2175 (2675 2000)(3200 2000);
WIRE 3 2175 (3200 2450)(3200 2000);
WIRE 3 2175 (2675 2450)(2675 2000);
WIRE 3 2175 (2675 2450)(3200 2450);
WIRE 16 -1 (2900 1900)(2900 1950);
WIRE 16 -1 (3800 1950)(2900 1950);
WIRE 16 -1 (2325 1950)(2900 1950);
FORCEPROP 2 LAST SIG_NAME VR_PVDDQ_GHJ_PH1_SW
J 0
(2460 1960);
DISPLAY 0.617021 (2460 1960);
PAINT ORANGE (2460 1960);
FORCEPROP 2 LASTPROP $XRERR UNIQUE?
J 0
(2220 1960);
DISPLAY 0.638298 (2220 1960);
PAINT MONO (2220 1960);
DISPLAY INVISIBLE (2220 1960);
WIRE 3 2175 (2725 1925)(3500 1925);
WIRE 3 2175 (3500 1925)(3500 1225);
WIRE 3 2175 (2725 1925)(2725 1225);
WIRE 3 2175 (2725 1225)(3500 1225);
WIRE 16 -1 (2900 1700)(2900 1650);
WIRE 16 -1 (2900 1600)(2900 1650);
WIRE 16 -1 (3400 1650)(2900 1650);
FORCEPROP 2 LAST SIG_NAME VR_PVDDQ_GHJ_PH1_SW_RC
J 0
(2935 1660);
DISPLAY 0.617021 (2935 1660);
PAINT ORANGE (2935 1660);
FORCEPROP 2 LASTPROP $XRERR UNIQUE?
J 0
(3430 1650);
DISPLAY 0.638298 (3430 1650);
PAINT MONO (3430 1650);
DISPLAY INVISIBLE (3430 1650);
WIRE 16 -1 (-1525 2150)(1325 2150);
WIRE 16 -1 (350 2300)(1325 2300);
FORCEPROP 0 LAST SIG_NAME TP_PVDDQ_GHJ_PH1_GL_1
J 0
(377 2315);
DISPLAY 0.617021 (377 2315);
PAINT ORANGE (377 2315);
FORCEPROP 2 LASTPROP $XRERR UNIQUE?
J 0
(110 2300);
DISPLAY 0.638298 (110 2300);
PAINT MONO (110 2300);
DISPLAY INVISIBLE (110 2300);
WIRE 16 -1 (1050 1825)(1050 2050);
WIRE 16 -1 (1325 2050)(1050 2050);
WIRE 16 -1 (1050 2050)(1050 3150);
WIRE 16 -1 (1050 3150)(3700 3150);
FORCEPROP 2 LAST SIG_NAME VR_PVDDQ_GHJ_AIREF1
J 0
(3010 3164);
DISPLAY 0.617021 (3010 3164);
PAINT ORANGE (3010 3164);
WIRE 3 2175 (-100 1800)(275 1800);
WIRE 3 2175 (275 2125)(275 1800);
WIRE 3 2175 (-100 2125)(-100 1800);
WIRE 3 2175 (-100 2125)(275 2125);
WIRE 16 -1 (-925 3050)(-800 3050);
WIRE 16 -1 (-925 2600)(-925 2800);
WIRE 16 -1 (-925 2800)(-925 3050);
WIRE 16 -1 (-925 2800)(1325 2800);
FORCEPROP 2 LAST SIG_NAME VR_PVDDQ_GHJ_PH1_VCIN
J 0
(-840 2810);
DISPLAY 0.617021 (-840 2810);
PAINT ORANGE (-840 2810);
FORCEPROP 2 LASTPROP $XRERR UNIQUE?
J 0
(-1080 2810);
DISPLAY 0.638298 (-1080 2810);
PAINT MONO (-1080 2810);
DISPLAY INVISIBLE (-1080 2810);
WIRE 3 682 (-325 2350)(-425 2350);
WIRE 3 682 (-425 2350)(-425 2625);
WIRE 3 682 (-325 2625)(-325 2350);
WIRE 3 682 (-325 2625)(-425 2625);
WIRE 16 -1 (2325 2800)(3625 2800);
FORCEPROP 2 LAST SIG_NAME ISENSE_PVDDQ_GHJ_PH1_IMON
J 0
(2712 2810);
DISPLAY 0.617021 (2712 2810);
PAINT ORANGE (2712 2810);
WIRE 16 -1 (4625 2500)(4625 2600);
WIRE 16 -1 (2325 2600)(4625 2600);
FORCEPROP 0 LAST VOLTAGE 3.6
J 0
(2400 2675);
DISPLAY 1.021277 (2400 2675);
PAINT SKYBLUE (2400 2675);
DISPLAY INVISIBLE (2400 2675);
FORCEPROP 2 LAST SIG_NAME VR_PVDDQ_GHJ_PH1_OCSET
J 0
(2457 2616);
DISPLAY 0.617021 (2457 2616);
PAINT ORANGE (2457 2616);
FORCEPROP 2 LASTPROP $XRERR UNIQUE?
J 0
(2217 2616);
DISPLAY 0.638298 (2217 2616);
PAINT MONO (2217 2616);
DISPLAY INVISIBLE (2217 2616);
WIRE 16 -1 (950 1950)(1325 1950);
WIRE 16 -1 (950 2000)(950 1950);
WIRE 16 -1 (200 2000)(950 2000);
FORCEPROP 2 LAST SIG_NAME VR_PVDDQ_GHJ_PH1_BOOT_R
J 0
(310 2010);
DISPLAY 0.617021 (310 2010);
PAINT ORANGE (310 2010);
FORCEPROP 2 LASTPROP $XRERR UNIQUE?
J 0
(70 2010);
DISPLAY 0.638298 (70 2010);
PAINT MONO (70 2010);
DISPLAY INVISIBLE (70 2010);
WIRE 16 2175 (-525 2675)(225 2675);
WIRE 16 2175 (225 2675)(225 2275);
WIRE 16 2175 (-525 2675)(-525 2275);
WIRE 16 2175 (-525 2275)(225 2275);
WIRE 3 682 (-200 0)(-300 0);
WIRE 3 682 (-200 275)(-200 0);
WIRE 3 682 (-300 0)(-300 275);
WIRE 3 682 (-300 275)(-200 275);
WIRE 16 -1 (1100 -475)(1350 -475);
WIRE 16 -1 (1100 -650)(1100 -475);
WIRE 16 -1 (-625 -650)(-625 -575);
WIRE 16 -1 (-625 -650)(1100 -650);
FORCEPROP 2 LAST SIG_NAME VR_PVDDQ_GHJ_PH2_PHASE
J 0
(-515 -640);
DISPLAY 0.617021 (-515 -640);
PAINT ORANGE (-515 -640);
FORCEPROP 2 LASTPROP $XRERR UNIQUE?
J 0
(-755 -640);
DISPLAY 0.638298 (-755 -640);
PAINT MONO (-755 -640);
DISPLAY INVISIBLE (-755 -640);
WIRE 16 -1 (3250 -800)(3250 -775);
WIRE 16 -1 (3250 -775)(3250 -725);
WIRE 16 -1 (2550 -775)(3250 -775);
FORCEPROP 2 LAST SIG_NAME VR_PVDDQ_GHJ_PH2_SW_RC
J 0
(2560 -765);
DISPLAY 0.617021 (2560 -765);
PAINT ORANGE (2560 -765);
FORCEPROP 2 LASTPROP $XRERR UNIQUE?
J 0
(2310 -775);
DISPLAY 0.638298 (2310 -775);
PAINT MONO (2310 -775);
DISPLAY INVISIBLE (2310 -775);
WIRE 16 -1 (2350 -425)(3250 -425);
FORCEPROP 2 LAST SIG_NAME VR_PVDDQ_GHJ_PH2_SW
J 0
(2710 -415);
DISPLAY 0.617021 (2710 -415);
PAINT ORANGE (2710 -415);
FORCEPROP 2 LASTPROP $XRERR UNIQUE?
J 0
(2470 -415);
DISPLAY 0.638298 (2470 -415);
PAINT MONO (2470 -415);
DISPLAY INVISIBLE (2470 -415);
WIRE 16 -1 (3250 -525)(3250 -425);
WIRE 16 -1 (3250 -425)(3750 -425);
WIRE 3 2175 (-875 2900)(-525 2900);
WIRE 3 2175 (-525 3150)(-525 2900);
WIRE 3 2175 (-875 3150)(-875 2900);
WIRE 3 2175 (-875 3150)(-525 3150);
WIRE 16 -1 (1150 775)(3925 775);
FORCEPROP 2 LAST SIG_NAME VR_PVDDQ_GHJ_AIREF2
J 0
(2585 789);
DISPLAY 0.617021 (2585 789);
PAINT ORANGE (2585 789);
WIRE 16 -1 (1150 -525)(1150 -325);
WIRE 16 -1 (1350 -325)(1150 -325);
WIRE 16 -1 (1150 -325)(1150 775);
WIRE 16 -1 (375 -75)(1350 -75);
FORCEPROP 0 LAST SIG_NAME TP_PVDDQ_GHJ_PH2_GL_1
J 0
(402 -60);
DISPLAY 0.617021 (402 -60);
PAINT ORANGE (402 -60);
FORCEPROP 2 LASTPROP $XRERR UNIQUE?
J 0
(135 -75);
DISPLAY 0.638298 (135 -75);
PAINT MONO (135 -75);
DISPLAY INVISIBLE (135 -75);
WIRE 3 2175 (2175 -1125)(3625 -1125);
WIRE 3 2175 (3625 -475)(3625 -1125);
WIRE 3 2175 (2175 -475)(2175 -1125);
WIRE 3 2175 (2175 -475)(3625 -475);
WIRE 3 2175 (2825 -350)(3375 -350);
WIRE 3 2175 (3375 75)(3375 -350);
WIRE 3 2175 (2825 75)(2825 -350);
WIRE 3 2175 (2825 75)(3375 75);
WIRE 16 -1 (1100 -425)(1350 -425);
WIRE 16 -1 (1100 -325)(375 -325);
FORCEPROP 2 LAST SIG_NAME VR_PVDDQ_GHJ_PH2_BOOT_R
J 0
(485 -315);
DISPLAY 0.617021 (485 -315);
PAINT ORANGE (485 -315);
FORCEPROP 2 LASTPROP $XRERR UNIQUE?
J 0
(245 -315);
DISPLAY 0.638298 (245 -315);
PAINT MONO (245 -315);
DISPLAY INVISIBLE (245 -315);
WIRE 16 -1 (1100 -325)(1100 -425);
WIRE 16 -1 (-625 -325)(-625 -375);
WIRE 16 -1 (-625 -325)(175 -325);
FORCEPROP 2 LAST SIG_NAME VR_PVDDQ_GHJ_PH2_BOOT
J 0
(-565 -315);
DISPLAY 0.617021 (-565 -315);
PAINT ORANGE (-565 -315);
FORCEPROP 2 LASTPROP $XRERR UNIQUE?
J 0
(-805 -315);
DISPLAY 0.638298 (-805 -315);
PAINT MONO (-805 -315);
DISPLAY INVISIBLE (-805 -315);
WIRE 16 -1 (375 -125)(1350 -125);
FORCEPROP 0 LAST SIG_NAME TP_PVDDQ_GHJ_PH2_GL_0
J 0
(402 -110);
DISPLAY 0.617021 (402 -110);
PAINT ORANGE (402 -110);
FORCEPROP 2 LASTPROP $XRERR UNIQUE?
J 0
(135 -125);
DISPLAY 0.638298 (135 -125);
PAINT MONO (135 -125);
DISPLAY INVISIBLE (135 -125);
WIRE 16 -1 (3050 25)(3050 100);
WIRE 16 -1 (3050 100)(3775 100);
WIRE 16 -1 (2350 100)(2350 -75);
WIRE 16 -1 (2350 100)(3050 100);
FORCEPROP 2 LAST SIG_NAME A_TSENSE_PVDDQ_GHJ
J 0
(2387 110);
DISPLAY 0.617021 (2387 110);
PAINT ORANGE (2387 110);
WIRE 16 -1 (4650 125)(4650 225);
WIRE 16 -1 (2350 225)(4650 225);
FORCEPROP 0 LAST VOLTAGE 3.6
J 0
(2425 300);
DISPLAY 1.021277 (2425 300);
PAINT SKYBLUE (2425 300);
DISPLAY INVISIBLE (2425 300);
FORCEPROP 2 LAST SIG_NAME VR_PVDDQ_GHJ_PH2_OCSET
J 0
(2482 241);
DISPLAY 0.617021 (2482 241);
PAINT ORANGE (2482 241);
FORCEPROP 2 LASTPROP $XRERR UNIQUE?
J 0
(2242 241);
DISPLAY 0.638298 (2242 241);
PAINT MONO (2242 241);
DISPLAY INVISIBLE (2242 241);
WIRE 16 -1 (2350 425)(3950 425);
FORCEPROP 2 LAST SIG_NAME ISENSE_PVDDQ_GHJ_PH2_IMON
J 0
(2987 435);
DISPLAY 0.617021 (2987 435);
PAINT ORANGE (2987 435);
WIRE 16 -1 (0 2000)(-775 2000);
FORCEPROP 2 LAST SIG_NAME VR_PVDDQ_GHJ_PH1_BOOT
J 0
(-740 2010);
DISPLAY 0.617021 (-740 2010);
PAINT ORANGE (-740 2010);
FORCEPROP 2 LASTPROP $XRERR UNIQUE?
J 0
(-980 2010);
DISPLAY 0.638298 (-980 2010);
PAINT MONO (-980 2010);
DISPLAY INVISIBLE (-980 2010);
WIRE 16 -1 (950 1900)(1325 1900);
WIRE 16 -1 (950 1725)(950 1900);
WIRE 16 -1 (-775 1725)(-775 1800);
WIRE 16 -1 (-775 1725)(950 1725);
FORCEPROP 2 LAST SIG_NAME VR_PVDDQ_GHJ_PH1_PHASE
J 0
(-690 1735);
DISPLAY 0.617021 (-690 1735);
PAINT ORANGE (-690 1735);
FORCEPROP 2 LASTPROP $XRERR UNIQUE?
J 0
(-930 1735);
DISPLAY 0.638298 (-930 1735);
PAINT MONO (-930 1735);
DISPLAY INVISIBLE (-930 1735);
WIRE 16 2175 (-1125 1675)(-200 1675);
WIRE 16 2175 (-200 2075)(-200 1675);
WIRE 16 2175 (-1125 2075)(-1125 1675);
WIRE 16 2175 (-1125 2075)(-200 2075);
DOT 1 (-1650 325);
DOT 1 (-2200 325);
DOT 1 (-250 675);
DOT 1 (-1925 -150);
DOT 1 (-1100 -150);
DOT 1 (-1375 -150);
DOT 1 (-925 2800);
DOT 1 (4400 -425);
DOT 1 (4500 -425);
DOT 1 (3250 -775);
DOT 1 (3250 -425);
DOT 1 (4400 1950);
DOT 1 (4500 1950);
DOT 1 (2900 1650);
DOT 1 (2900 1950);
DOT 1 (1175 2600);
DOT 1 (2675 1800);
DOT 1 (1075 325);
DOT 1 (2500 -625);
DOT 1 (-1175 2700);
DOT 1 (-1175 2200);
DOT 1 (-1425 2200);
DOT 1 (-1425 2700);
DOT 1 (-1650 2200);
DOT 1 (-1650 2700);
DOT 1 (-1900 2200);
DOT 1 (-1900 2700);
DOT 1 (1050 2050);
DOT 1 (-2200 -150);
DOT 1 (-1950 2200);
DOT 1 (-1700 2700);
DOT 1 (-925 2200);
DOT 1 (350 3050);
DOT 1 (2500 -675);
DOT 1 (2500 -575);
DOT 1 (550 675);
DOT 1 (1275 225);
DOT 1 (1075 2700);
DOT 1 (3050 100);
DOT 1 (2675 1700);
DOT 1 (2675 1750);
DOT 1 (2950 2475);
DOT 1 (-1925 325);
DOT 1 (-1100 325);
DOT 1 (-1375 325);
DOT 1 (-800 425);
DOT 1 (-800 -150);
DOT 1 (25 3050);
DOT 1 (-250 -150);
DOT 1 (-375 3050);
DOT 1 (-375 2200);
DOT 1 (-1650 -150);
DOT 1 (1150 -325);
DOT 1 (100 675);
FORCENOTE
TP FAB4 POP CAP ON SS BOM 20170208
(-2350 -300) 0;
DISPLAY LEFT (-2350 -300);
DISPLAY 0.638298 (-2350 -300);
PAINT RED (-2350 -300);
FORCENOTE
TP FAB1 CHANGE PN 0310
(-225 350) 0;
DISPLAY LEFT (-225 350);
DISPLAY 1.021277 (-225 350);
PAINT RED (-225 350);
FORCENOTE
PLACE ON TOP
(-480 -175) 0;
DISPLAY LEFT (-480 -175);
DISPLAY 1.553191 (-480 -175);
PAINT PURPLE (-480 -175);
FORCENOTE
TP FAB3 CHANGE L1F2 0823
(3650 -175) 0;
DISPLAY LEFT (3650 -175);
DISPLAY 0.638298 (3650 -175);
PAINT RED (3650 -175);
FORCENOTE
TP FAB1 NC 0321
(2450 150) 0;
DISPLAY LEFT (2450 150);
DISPLAY 1.021277 (2450 150);
PAINT RED (2450 150);
FORCENOTE
TP FAB3-DVT CHANGE L1G1 IND FOR SS BOM 20161215
(3750 1475) 0;
DISPLAY LEFT (3750 1475);
DISPLAY 0.638298 (3750 1475);
PAINT RED (3750 1475);
FORCENOTE
TP FAB1 CO-LAY WITH TI PARTS 11/16
(3250 2250) 0;
DISPLAY LEFT (3250 2250);
DISPLAY 0.851064 (3250 2250);
PAINT RED (3250 2250);
FORCENOTE
TP FAB1 CHANGE L1G1 PN 0122
(3400 2150) 0;
DISPLAY LEFT (3400 2150);
DISPLAY 0.638298 (3400 2150);
PAINT RED (3400 2150);
FORCENOTE
TP FAB3 CHANGE L1G1 0823
(3400 2100) 0;
DISPLAY LEFT (3400 2100);
DISPLAY 0.638298 (3400 2100);
PAINT RED (3400 2100);
FORCENOTE
TP FAB1 CO-LAY WITH TI PARTS 11/16
(2725 1100) 0;
DISPLAY LEFT (2725 1100);
DISPLAY 0.680851 (2725 1100);
PAINT RED (2725 1100);
FORCENOTE
TP FAB1 CHANGE RES TO 1 OHM 0603 0107
(2725 1150) 0;
DISPLAY LEFT (2725 1150);
DISPLAY 0.638298 (2725 1150);
PAINT RED (2725 1150);
FORCENOTE
TP FAB1 ADD NET NAME 12/04
(3100 1600) 0;
DISPLAY LEFT (3100 1600);
DISPLAY 0.680851 (3100 1600);
PAINT RED (3100 1600);
FORCENOTE
PLACE ON TOP
(-530 2200) 0;
DISPLAY LEFT (-530 2200);
DISPLAY 1.553191 (-530 2200);
PAINT PURPLE (-530 2200);
FORCENOTE
TDA21470
(1650 2875) 0;
DISPLAY LEFT (1650 2875);
DISPLAY 1.021277 (1650 2875);
PAINT SKYBLUE (1650 2875);
FORCENOTE
TDA21470
(1675 500) 0;
DISPLAY LEFT (1675 500);
DISPLAY 1.021277 (1675 500);
PAINT SKYBLUE (1675 500);
FORCENOTE
TP FAB1 NC 0321
(2400 2550) 0;
DISPLAY LEFT (2400 2550);
DISPLAY 1.021277 (2400 2550);
PAINT RED (2400 2550);
FORCENOTE
TP FAB1 CHANGE TO 0 OHM 0107
(-925 3150) 0;
DISPLAY LEFT (-925 3150);
DISPLAY 0.638298 (-925 3150);
PAINT RED (-925 3150);
FORCENOTE
SPOF
(-705 -775) 0;
DISPLAY LEFT (-705 -775);
DISPLAY 1.808511 (-705 -775);
PAINT PURPLE (-705 -775);
FORCENOTE
TP FAB1 CHANGE PN 0310
(-450 2700) 0;
DISPLAY LEFT (-450 2700);
DISPLAY 1.021277 (-450 2700);
PAINT RED (-450 2700);
FORCENOTE
ROOM = VDDQ_GHJ_PWR_VR
(-2480 -1500) 0;
DISPLAY LEFT (-2480 -1500);
DISPLAY 2.893617 (-2480 -1500);
PAINT PURPLE (-2480 -1500);
FORCENOTE
TP FAB1 ADD NET NAME 12/04
(3675 -1125) 0;
DISPLAY LEFT (3675 -1125);
DISPLAY 0.680851 (3675 -1125);
PAINT RED (3675 -1125);
FORCENOTE
TP FAB1 CHANGE L1F2 PN 0122
(3650 -125) 0;
DISPLAY LEFT (3650 -125);
DISPLAY 0.638298 (3650 -125);
PAINT RED (3650 -125);
FORCENOTE
TP FAB1 CO-LAY WITH TI PARTS 11/16
(-25 -800) 0;
DISPLAY LEFT (-25 -800);
DISPLAY 0.851064 (-25 -800);
PAINT RED (-25 -800);
FORCENOTE
TP FAB1 CHANGE RES TO 1 OHM 0603 0107
(3150 -1200) 0;
DISPLAY LEFT (3150 -1200);
DISPLAY 0.808511 (3150 -1200);
PAINT RED (3150 -1200);
FORCENOTE
TP FAB1 CO-LAY WITH TI PARTS 11/16
(3150 -1250) 0;
DISPLAY LEFT (3150 -1250);
DISPLAY 0.680851 (3150 -1250);
PAINT RED (3150 -1250);
FORCENOTE
TP FAB1 CHANGE TO 0 OHM 0107
(-875 800) 0;
DISPLAY LEFT (-875 800);
DISPLAY 0.638298 (-875 800);
PAINT RED (-875 800);
FORCENOTE
TP FAB3-DVT NOPOP L1F2 IND FOR SS BOM 20161215
(3650 -225) 0;
DISPLAY LEFT (3650 -225);
DISPLAY 0.638298 (3650 -225);
PAINT RED (3650 -225);
FORCENOTE
TP FAB1 CO-LAY WITH TI PARTS 11/16
(3425 0) 0;
DISPLAY LEFT (3425 0);
DISPLAY 0.553191 (3425 0);
PAINT RED (3425 0);
FORCENOTE
SPOF
(-730 1550) 0;
DISPLAY LEFT (-730 1550);
DISPLAY 1.936170 (-730 1550);
PAINT PURPLE (-730 1550);
FORCENOTE
TP FAB1 CO-LAY WITH TI PARTS 11/16
(-125 1525) 0;
DISPLAY LEFT (-125 1525);
DISPLAY 0.851064 (-125 1525);
PAINT RED (-125 1525);
FORCENOTE
TP FAB3-DVT NOPOP FROM SS BOM 20161215
(-2425 900) 0;
DISPLAY LEFT (-2425 900);
DISPLAY 1.021277 (-2425 900);
PAINT RED (-2425 900);
QUIT
